FILE_TYPE = MACRO_DRAWING;
SET COLOR_WIRE YELLOW;
SET COLOR_PROP MONO;
SET COLOR_DOT WHITE;
SET COLOR_ARC YELLOW;
SET COLOR_BODY GREEN;
SET COLOR_NOTE MONO;
SET PROP_DISPLAY VALUE;
SET PAGE_NUMBER P271;
FORCEADD GND..1
(-8425 4775);
FORCEPROP 3 LASTPIN (-8425 4825) SIG_NAME GND\g
J 0
(-8415 4835);
DISPLAY 0.659574 (-8415 4835);
PAINT MONO (-8415 4835);
DISPLAY INVISIBLE (-8415 4835);
FORCEPROP 1 LAST PATH I10
J 0
(-8350 4775);
DISPLAY 0.872340 (-8350 4775);
PAINT AQUA (-8350 4775);
DISPLAY INVISIBLE (-8350 4775);
FORCEPROP 1 LAST VOLTAGE 0.0V
J 0
(-8470 4732);
DISPLAY 0.340426 (-8470 4732);
PAINT SKYBLUE (-8470 4732);
DISPLAY INVISIBLE (-8470 4732);
FORCEPROP 1 LAST SIZE 1B
J 0
(-8350 4725);
DISPLAY 2.382979 (-8350 4725);
PAINT GREEN (-8350 4725);
DISPLAY INVISIBLE (-8350 4725);
FORCEPROP 1 LAST BODY_TYPE PLUMBING
J 0
(-8470 4732);
DISPLAY 0.340426 (-8470 4732);
PAINT GREEN (-8470 4732);
DISPLAY INVISIBLE (-8470 4732);
FORCEPROP 1 LAST HDL_POWER GND
J 0
(-8425 4925);
PAINT GREEN (-8425 4925);
DISPLAY INVISIBLE (-8425 4925);
FORCEPROP 2 LAST CDS_LIB mstr_symbols
J 0
(-8425 4775);
DISPLAY INVISIBLE (-8425 4775);
FORCEADD TPAD-DIFF-4P-GP..1
(-7950 4575);
FORCEPROP 1 LAST LOCATION T1P5
J 0
(-7925 4690);
DISPLAY 0.617021 (-7925 4690);
PAINT GREEN (-7925 4690);
FORCEPROP 2 LASTPIN (-8175 4525) $PN GND2
J 2
(-8185 4535);
DISPLAY 0.808511 (-8185 4535);
PAINT ORANGE (-8185 4535);
FORCEPROP 1 LAST VALUE TPAD-DIFF-4P-GP
J 0
(-8025 4445);
DISPLAY 0.617021 (-8025 4445);
PAINT GREEN (-8025 4445);
FORCEPROP 2 LASTPIN (-7725 4525) $PN 2
J 0
(-7715 4535);
DISPLAY 0.808511 (-7715 4535);
PAINT ORANGE (-7715 4535);
FORCEPROP 2 LASTPIN (-7725 4625) $PN 1
J 0
(-7715 4635);
DISPLAY 0.808511 (-7715 4635);
PAINT ORANGE (-7715 4635);
FORCEPROP 2 LASTPIN (-8175 4625) $PN GND1
J 2
(-8185 4635);
DISPLAY 0.808511 (-8185 4635);
PAINT ORANGE (-8185 4635);
FORCEPROP 1 LAST PATH I11
J 0
(-7950 4682);
DISPLAY 0.617021 (-7950 4682);
PAINT GREEN (-7950 4682);
DISPLAY INVISIBLE (-7950 4682);
FORCEPROP 1 LAST PART_NUMBER ZZ.00PAD.NW1
J 0
(-7950 4471);
DISPLAY 0.617021 (-7950 4471);
PAINT GREEN (-7950 4471);
DISPLAY INVISIBLE (-7950 4471);
FORCEPROP 1 LAST CDS_LMAN_SYM_OUTLINE -75,100,75,-100
J 0
(-7950 4575);
DISPLAY 0.468085 (-7950 4575);
PAINT GREEN (-7950 4575);
DISPLAY INVISIBLE (-7950 4575);
FORCEPROP 2 LAST CDS_LIB w_hdl
J 0
(-7950 4575);
DISPLAY INVISIBLE (-7950 4575);
FORCEPROP 1 LAST PACK_TYPE DISCRET-GB3
J 0
(-7950 4575);
DISPLAY 0.617021 (-7950 4575);
PAINT GREEN (-7950 4575);
DISPLAY INVISIBLE (-7950 4575);
FORCEPROP 2 LAST SEC 1
J 0
(-7925 4725);
DISPLAY 0.680851 (-7925 4725);
PAINT MONO (-7925 4725);
DISPLAY INVISIBLE (-7925 4725);
FORCEPROP 2 LAST SEC_TYPE DISCRET-GB3
J 0
(-7925 4725);
DISPLAY 1.021277 (-7925 4725);
PAINT ORANGE (-7925 4725);
DISPLAY INVISIBLE (-7925 4725);
FORCEADD GND..1
(-8400 4425);
FORCEPROP 3 LASTPIN (-8400 4475) SIG_NAME GND\g
J 0
(-8390 4485);
DISPLAY 0.659574 (-8390 4485);
PAINT MONO (-8390 4485);
DISPLAY INVISIBLE (-8390 4485);
FORCEPROP 1 LAST PATH I12
J 0
(-8325 4425);
DISPLAY 0.872340 (-8325 4425);
PAINT AQUA (-8325 4425);
DISPLAY INVISIBLE (-8325 4425);
FORCEPROP 1 LAST VOLTAGE 0.0V
J 0
(-8445 4382);
DISPLAY 0.340426 (-8445 4382);
PAINT SKYBLUE (-8445 4382);
DISPLAY INVISIBLE (-8445 4382);
FORCEPROP 1 LAST SIZE 1B
J 0
(-8325 4375);
DISPLAY 2.382979 (-8325 4375);
PAINT GREEN (-8325 4375);
DISPLAY INVISIBLE (-8325 4375);
FORCEPROP 1 LAST BODY_TYPE PLUMBING
J 0
(-8445 4382);
DISPLAY 0.340426 (-8445 4382);
PAINT GREEN (-8445 4382);
DISPLAY INVISIBLE (-8445 4382);
FORCEPROP 1 LAST HDL_POWER GND
J 0
(-8400 4575);
PAINT GREEN (-8400 4575);
DISPLAY INVISIBLE (-8400 4575);
FORCEPROP 2 LAST CDS_LIB mstr_symbols
J 0
(-8400 4425);
DISPLAY INVISIBLE (-8400 4425);
FORCEADD TPAD-DIFF-4P-GP..1
(-7950 4175);
FORCEPROP 1 LAST LOCATION T1P6
J 0
(-7925 4290);
DISPLAY 0.617021 (-7925 4290);
PAINT GREEN (-7925 4290);
FORCEPROP 2 LASTPIN (-8175 4225) $PN GND1
J 2
(-8185 4235);
DISPLAY 0.808511 (-8185 4235);
PAINT ORANGE (-8185 4235);
FORCEPROP 2 LASTPIN (-8175 4125) $PN GND2
J 2
(-8185 4135);
DISPLAY 0.808511 (-8185 4135);
PAINT ORANGE (-8185 4135);
FORCEPROP 1 LAST VALUE TPAD-DIFF-4P-GP
J 0
(-8025 4045);
DISPLAY 0.617021 (-8025 4045);
PAINT GREEN (-8025 4045);
FORCEPROP 2 LASTPIN (-7725 4125) $PN 2
J 0
(-7715 4135);
DISPLAY 0.808511 (-7715 4135);
PAINT ORANGE (-7715 4135);
FORCEPROP 2 LASTPIN (-7725 4225) $PN 1
J 0
(-7715 4235);
DISPLAY 0.808511 (-7715 4235);
PAINT ORANGE (-7715 4235);
FORCEPROP 1 LAST PATH I13
J 0
(-7950 4282);
DISPLAY 0.617021 (-7950 4282);
PAINT GREEN (-7950 4282);
DISPLAY INVISIBLE (-7950 4282);
FORCEPROP 1 LAST PART_NUMBER ZZ.00PAD.NW1
J 0
(-7950 4071);
DISPLAY 0.617021 (-7950 4071);
PAINT GREEN (-7950 4071);
DISPLAY INVISIBLE (-7950 4071);
FORCEPROP 1 LAST CDS_LMAN_SYM_OUTLINE -75,100,75,-100
J 0
(-7950 4175);
DISPLAY 0.468085 (-7950 4175);
PAINT GREEN (-7950 4175);
DISPLAY INVISIBLE (-7950 4175);
FORCEPROP 2 LAST CDS_LIB w_hdl
J 0
(-7950 4175);
DISPLAY INVISIBLE (-7950 4175);
FORCEPROP 1 LAST PACK_TYPE DISCRET-GB3
J 0
(-7950 4175);
DISPLAY 0.617021 (-7950 4175);
PAINT GREEN (-7950 4175);
DISPLAY INVISIBLE (-7950 4175);
FORCEPROP 2 LAST SEC 1
J 0
(-7925 4325);
DISPLAY 0.680851 (-7925 4325);
PAINT MONO (-7925 4325);
DISPLAY INVISIBLE (-7925 4325);
FORCEPROP 2 LAST SEC_TYPE DISCRET-GB3
J 0
(-7925 4325);
DISPLAY 1.021277 (-7925 4325);
PAINT ORANGE (-7925 4325);
DISPLAY INVISIBLE (-7925 4325);
FORCEADD GND..1
(-8400 4025);
FORCEPROP 3 LASTPIN (-8400 4075) SIG_NAME GND\g
J 0
(-8390 4085);
DISPLAY 0.659574 (-8390 4085);
PAINT MONO (-8390 4085);
DISPLAY INVISIBLE (-8390 4085);
FORCEPROP 2 LAST CDS_LIB mstr_symbols
J 0
(-8400 4025);
DISPLAY INVISIBLE (-8400 4025);
FORCEPROP 1 LAST PATH I14
J 0
(-8325 4025);
DISPLAY 0.872340 (-8325 4025);
PAINT AQUA (-8325 4025);
DISPLAY INVISIBLE (-8325 4025);
FORCEPROP 1 LAST VOLTAGE 0.0V
J 0
(-8445 3982);
DISPLAY 0.340426 (-8445 3982);
PAINT SKYBLUE (-8445 3982);
DISPLAY INVISIBLE (-8445 3982);
FORCEPROP 1 LAST SIZE 1B
J 0
(-8325 3975);
DISPLAY 2.382979 (-8325 3975);
PAINT GREEN (-8325 3975);
DISPLAY INVISIBLE (-8325 3975);
FORCEPROP 1 LAST BODY_TYPE PLUMBING
J 0
(-8445 3982);
DISPLAY 0.340426 (-8445 3982);
PAINT GREEN (-8445 3982);
DISPLAY INVISIBLE (-8445 3982);
FORCEPROP 1 LAST HDL_POWER GND
J 0
(-8400 4175);
PAINT GREEN (-8400 4175);
DISPLAY INVISIBLE (-8400 4175);
FORCEADD TPAD-DIFF-4P-GP..1
(-6000 4900);
FORCEPROP 1 LAST LOCATION T1P10
J 0
(-5975 5015);
DISPLAY 0.617021 (-5975 5015);
PAINT GREEN (-5975 5015);
FORCEPROP 2 LASTPIN (-5775 4950) $PN 1
J 0
(-5765 4960);
DISPLAY 0.808511 (-5765 4960);
PAINT ORANGE (-5765 4960);
FORCEPROP 2 LASTPIN (-6225 4850) $PN GND2
J 2
(-6235 4860);
DISPLAY 0.808511 (-6235 4860);
PAINT ORANGE (-6235 4860);
FORCEPROP 2 LASTPIN (-6225 4950) $PN GND1
J 2
(-6235 4960);
DISPLAY 0.808511 (-6235 4960);
PAINT ORANGE (-6235 4960);
FORCEPROP 2 LASTPIN (-5775 4850) $PN 2
J 0
(-5765 4860);
DISPLAY 0.808511 (-5765 4860);
PAINT ORANGE (-5765 4860);
FORCEPROP 1 LAST VALUE TPAD-DIFF-4P-GP
J 0
(-6075 4770);
DISPLAY 0.617021 (-6075 4770);
PAINT GREEN (-6075 4770);
FORCEPROP 1 LAST PATH I15
J 0
(-6000 5007);
DISPLAY 0.617021 (-6000 5007);
PAINT GREEN (-6000 5007);
DISPLAY INVISIBLE (-6000 5007);
FORCEPROP 1 LAST PART_NUMBER ZZ.00PAD.NW1
J 0
(-6000 4796);
DISPLAY 0.617021 (-6000 4796);
PAINT GREEN (-6000 4796);
DISPLAY INVISIBLE (-6000 4796);
FORCEPROP 1 LAST CDS_LMAN_SYM_OUTLINE -75,100,75,-100
J 0
(-6000 4900);
DISPLAY 0.468085 (-6000 4900);
PAINT GREEN (-6000 4900);
DISPLAY INVISIBLE (-6000 4900);
FORCEPROP 2 LAST CDS_LIB w_hdl
J 0
(-6000 4900);
DISPLAY INVISIBLE (-6000 4900);
FORCEPROP 1 LAST PACK_TYPE DISCRET-GB3
J 0
(-6000 4900);
DISPLAY 0.617021 (-6000 4900);
PAINT GREEN (-6000 4900);
DISPLAY INVISIBLE (-6000 4900);
FORCEPROP 2 LAST SEC 1
J 0
(-5975 5050);
DISPLAY 0.680851 (-5975 5050);
PAINT MONO (-5975 5050);
DISPLAY INVISIBLE (-5975 5050);
FORCEPROP 2 LAST SEC_TYPE DISCRET-GB3
J 0
(-5975 5050);
DISPLAY 1.021277 (-5975 5050);
PAINT ORANGE (-5975 5050);
DISPLAY INVISIBLE (-5975 5050);
FORCEADD TPAD-DIFF-4P-GP..1
(-6000 5675);
FORCEPROP 1 LAST LOCATION T1P8
J 0
(-5975 5790);
DISPLAY 0.617021 (-5975 5790);
PAINT GREEN (-5975 5790);
FORCEPROP 1 LAST VALUE TPAD-DIFF-4P-GP
J 0
(-6075 5545);
DISPLAY 0.617021 (-6075 5545);
PAINT GREEN (-6075 5545);
FORCEPROP 2 LASTPIN (-5775 5725) $PN 1
J 0
(-5765 5735);
DISPLAY 0.808511 (-5765 5735);
PAINT ORANGE (-5765 5735);
FORCEPROP 2 LASTPIN (-6225 5625) $PN GND2
J 2
(-6235 5635);
DISPLAY 0.808511 (-6235 5635);
PAINT ORANGE (-6235 5635);
FORCEPROP 2 LASTPIN (-5775 5625) $PN 2
J 0
(-5765 5635);
DISPLAY 0.808511 (-5765 5635);
PAINT ORANGE (-5765 5635);
FORCEPROP 2 LASTPIN (-6225 5725) $PN GND1
J 2
(-6235 5735);
DISPLAY 0.808511 (-6235 5735);
PAINT ORANGE (-6235 5735);
FORCEPROP 1 LAST PATH I16
J 0
(-6000 5782);
DISPLAY 0.617021 (-6000 5782);
PAINT GREEN (-6000 5782);
DISPLAY INVISIBLE (-6000 5782);
FORCEPROP 1 LAST PART_NUMBER ZZ.00PAD.NW1
J 0
(-6000 5571);
DISPLAY 0.617021 (-6000 5571);
PAINT GREEN (-6000 5571);
DISPLAY INVISIBLE (-6000 5571);
FORCEPROP 1 LAST CDS_LMAN_SYM_OUTLINE -75,100,75,-100
J 0
(-6000 5675);
DISPLAY 0.468085 (-6000 5675);
PAINT GREEN (-6000 5675);
DISPLAY INVISIBLE (-6000 5675);
FORCEPROP 2 LAST CDS_LIB w_hdl
J 0
(-6000 5675);
DISPLAY INVISIBLE (-6000 5675);
FORCEPROP 1 LAST PACK_TYPE DISCRET-GB3
J 0
(-6000 5675);
DISPLAY 0.617021 (-6000 5675);
PAINT GREEN (-6000 5675);
DISPLAY INVISIBLE (-6000 5675);
FORCEPROP 2 LAST SEC 1
J 0
(-5975 5825);
DISPLAY 0.680851 (-5975 5825);
PAINT MONO (-5975 5825);
DISPLAY INVISIBLE (-5975 5825);
FORCEPROP 2 LAST SEC_TYPE DISCRET-GB3
J 0
(-5975 5825);
DISPLAY 1.021277 (-5975 5825);
PAINT ORANGE (-5975 5825);
DISPLAY INVISIBLE (-5975 5825);
FORCEADD TPAD-DIFF-4P-GP..1
(-6000 6075);
FORCEPROP 1 LAST LOCATION T1P7
J 0
(-5975 6190);
DISPLAY 0.617021 (-5975 6190);
PAINT GREEN (-5975 6190);
FORCEPROP 1 LAST VALUE TPAD-DIFF-4P-GP
J 0
(-6075 5945);
DISPLAY 0.617021 (-6075 5945);
PAINT GREEN (-6075 5945);
FORCEPROP 2 LASTPIN (-5775 6125) $PN 1
J 0
(-5765 6135);
DISPLAY 0.808511 (-5765 6135);
PAINT ORANGE (-5765 6135);
FORCEPROP 2 LASTPIN (-6225 6025) $PN GND2
J 2
(-6235 6035);
DISPLAY 0.808511 (-6235 6035);
PAINT ORANGE (-6235 6035);
FORCEPROP 2 LASTPIN (-6225 6125) $PN GND1
J 2
(-6235 6135);
DISPLAY 0.808511 (-6235 6135);
PAINT ORANGE (-6235 6135);
FORCEPROP 2 LASTPIN (-5775 6025) $PN 2
J 0
(-5765 6035);
DISPLAY 0.808511 (-5765 6035);
PAINT ORANGE (-5765 6035);
FORCEPROP 1 LAST PATH I17
J 0
(-6000 6182);
DISPLAY 0.617021 (-6000 6182);
PAINT GREEN (-6000 6182);
DISPLAY INVISIBLE (-6000 6182);
FORCEPROP 1 LAST PART_NUMBER ZZ.00PAD.NW1
J 0
(-6000 5971);
DISPLAY 0.617021 (-6000 5971);
PAINT GREEN (-6000 5971);
DISPLAY INVISIBLE (-6000 5971);
FORCEPROP 1 LAST CDS_LMAN_SYM_OUTLINE -75,100,75,-100
J 0
(-6000 6075);
DISPLAY 0.468085 (-6000 6075);
PAINT GREEN (-6000 6075);
DISPLAY INVISIBLE (-6000 6075);
FORCEPROP 2 LAST CDS_LIB w_hdl
J 0
(-6000 6075);
DISPLAY INVISIBLE (-6000 6075);
FORCEPROP 1 LAST PACK_TYPE DISCRET-GB3
J 0
(-6000 6075);
DISPLAY 0.617021 (-6000 6075);
PAINT GREEN (-6000 6075);
DISPLAY INVISIBLE (-6000 6075);
FORCEPROP 2 LAST SEC 1
J 0
(-5975 6225);
DISPLAY 0.680851 (-5975 6225);
PAINT MONO (-5975 6225);
DISPLAY INVISIBLE (-5975 6225);
FORCEPROP 2 LAST SEC_TYPE DISCRET-GB3
J 0
(-5975 6225);
DISPLAY 1.021277 (-5975 6225);
PAINT ORANGE (-5975 6225);
DISPLAY INVISIBLE (-5975 6225);
FORCEADD GND..1
(-6450 5925);
FORCEPROP 3 LASTPIN (-6450 5975) SIG_NAME GND\g
J 0
(-6440 5985);
DISPLAY 0.659574 (-6440 5985);
PAINT MONO (-6440 5985);
DISPLAY INVISIBLE (-6440 5985);
FORCEPROP 1 LAST PATH I18
J 0
(-6375 5925);
DISPLAY 0.872340 (-6375 5925);
PAINT AQUA (-6375 5925);
DISPLAY INVISIBLE (-6375 5925);
FORCEPROP 1 LAST VOLTAGE 0.0V
J 0
(-6495 5882);
DISPLAY 0.340426 (-6495 5882);
PAINT SKYBLUE (-6495 5882);
DISPLAY INVISIBLE (-6495 5882);
FORCEPROP 1 LAST SIZE 1B
J 0
(-6375 5875);
DISPLAY 2.382979 (-6375 5875);
PAINT GREEN (-6375 5875);
DISPLAY INVISIBLE (-6375 5875);
FORCEPROP 1 LAST BODY_TYPE PLUMBING
J 0
(-6495 5882);
DISPLAY 0.340426 (-6495 5882);
PAINT GREEN (-6495 5882);
DISPLAY INVISIBLE (-6495 5882);
FORCEPROP 1 LAST HDL_POWER GND
J 0
(-6450 6075);
PAINT GREEN (-6450 6075);
DISPLAY INVISIBLE (-6450 6075);
FORCEPROP 2 LAST CDS_LIB mstr_symbols
J 0
(-6450 5925);
DISPLAY INVISIBLE (-6450 5925);
FORCEADD TPAD-DIFF-4P-GP..1
(-6000 5300);
FORCEPROP 1 LAST VALUE TPAD-DIFF-4P-GP
J 0
(-6075 5170);
DISPLAY 0.617021 (-6075 5170);
PAINT GREEN (-6075 5170);
FORCEPROP 2 LASTPIN (-5775 5350) $PN 1
J 0
(-5765 5360);
DISPLAY 0.808511 (-5765 5360);
PAINT ORANGE (-5765 5360);
FORCEPROP 2 LASTPIN (-6225 5250) $PN GND2
J 2
(-6235 5260);
DISPLAY 0.808511 (-6235 5260);
PAINT ORANGE (-6235 5260);
FORCEPROP 2 LASTPIN (-6225 5350) $PN GND1
J 2
(-6235 5360);
DISPLAY 0.808511 (-6235 5360);
PAINT ORANGE (-6235 5360);
FORCEPROP 2 LASTPIN (-5775 5250) $PN 2
J 0
(-5765 5260);
DISPLAY 0.808511 (-5765 5260);
PAINT ORANGE (-5765 5260);
FORCEPROP 1 LAST LOCATION T1P9
J 0
(-5975 5415);
DISPLAY 0.617021 (-5975 5415);
PAINT GREEN (-5975 5415);
FORCEPROP 1 LAST PATH I19
J 0
(-6000 5407);
DISPLAY 0.617021 (-6000 5407);
PAINT GREEN (-6000 5407);
DISPLAY INVISIBLE (-6000 5407);
FORCEPROP 1 LAST PART_NUMBER ZZ.00PAD.NW1
J 0
(-6000 5196);
DISPLAY 0.617021 (-6000 5196);
PAINT GREEN (-6000 5196);
DISPLAY INVISIBLE (-6000 5196);
FORCEPROP 1 LAST CDS_LMAN_SYM_OUTLINE -75,100,75,-100
J 0
(-6000 5300);
DISPLAY 0.468085 (-6000 5300);
PAINT GREEN (-6000 5300);
DISPLAY INVISIBLE (-6000 5300);
FORCEPROP 2 LAST CDS_LIB w_hdl
J 0
(-6000 5300);
DISPLAY INVISIBLE (-6000 5300);
FORCEPROP 1 LAST PACK_TYPE DISCRET-GB3
J 0
(-6000 5300);
DISPLAY 0.617021 (-6000 5300);
PAINT GREEN (-6000 5300);
DISPLAY INVISIBLE (-6000 5300);
FORCEPROP 2 LAST SEC 1
J 0
(-5975 5450);
DISPLAY 0.680851 (-5975 5450);
PAINT MONO (-5975 5450);
DISPLAY INVISIBLE (-5975 5450);
FORCEPROP 2 LAST SEC_TYPE DISCRET-GB3
J 0
(-5975 5450);
DISPLAY 1.021277 (-5975 5450);
PAINT ORANGE (-5975 5450);
DISPLAY INVISIBLE (-5975 5450);
FORCEADD GND..1
(-6450 5525);
FORCEPROP 3 LASTPIN (-6450 5575) SIG_NAME GND\g
J 0
(-6440 5585);
DISPLAY 0.659574 (-6440 5585);
PAINT MONO (-6440 5585);
DISPLAY INVISIBLE (-6440 5585);
FORCEPROP 1 LAST PATH I20
J 0
(-6375 5525);
DISPLAY 0.872340 (-6375 5525);
PAINT AQUA (-6375 5525);
DISPLAY INVISIBLE (-6375 5525);
FORCEPROP 1 LAST VOLTAGE 0.0V
J 0
(-6495 5482);
DISPLAY 0.340426 (-6495 5482);
PAINT SKYBLUE (-6495 5482);
DISPLAY INVISIBLE (-6495 5482);
FORCEPROP 1 LAST SIZE 1B
J 0
(-6375 5475);
DISPLAY 2.382979 (-6375 5475);
PAINT GREEN (-6375 5475);
DISPLAY INVISIBLE (-6375 5475);
FORCEPROP 1 LAST BODY_TYPE PLUMBING
J 0
(-6495 5482);
DISPLAY 0.340426 (-6495 5482);
PAINT GREEN (-6495 5482);
DISPLAY INVISIBLE (-6495 5482);
FORCEPROP 1 LAST HDL_POWER GND
J 0
(-6450 5675);
PAINT GREEN (-6450 5675);
DISPLAY INVISIBLE (-6450 5675);
FORCEPROP 2 LAST CDS_LIB mstr_symbols
J 0
(-6450 5525);
DISPLAY INVISIBLE (-6450 5525);
FORCEADD GND..1
(-6450 5150);
FORCEPROP 3 LASTPIN (-6450 5200) SIG_NAME GND\g
J 0
(-6440 5210);
DISPLAY 0.659574 (-6440 5210);
PAINT MONO (-6440 5210);
DISPLAY INVISIBLE (-6440 5210);
FORCEPROP 1 LAST PATH I21
J 0
(-6375 5150);
DISPLAY 0.872340 (-6375 5150);
PAINT AQUA (-6375 5150);
DISPLAY INVISIBLE (-6375 5150);
FORCEPROP 1 LAST VOLTAGE 0.0V
J 0
(-6495 5107);
DISPLAY 0.340426 (-6495 5107);
PAINT SKYBLUE (-6495 5107);
DISPLAY INVISIBLE (-6495 5107);
FORCEPROP 1 LAST SIZE 1B
J 0
(-6375 5100);
DISPLAY 2.382979 (-6375 5100);
PAINT GREEN (-6375 5100);
DISPLAY INVISIBLE (-6375 5100);
FORCEPROP 1 LAST BODY_TYPE PLUMBING
J 0
(-6495 5107);
DISPLAY 0.340426 (-6495 5107);
PAINT GREEN (-6495 5107);
DISPLAY INVISIBLE (-6495 5107);
FORCEPROP 1 LAST HDL_POWER GND
J 0
(-6450 5300);
PAINT GREEN (-6450 5300);
DISPLAY INVISIBLE (-6450 5300);
FORCEPROP 2 LAST CDS_LIB mstr_symbols
J 0
(-6450 5150);
DISPLAY INVISIBLE (-6450 5150);
FORCEADD GND..1
(-6450 4750);
FORCEPROP 3 LASTPIN (-6450 4800) SIG_NAME GND\g
J 0
(-6440 4810);
DISPLAY 0.659574 (-6440 4810);
PAINT MONO (-6440 4810);
DISPLAY INVISIBLE (-6440 4810);
FORCEPROP 1 LAST PATH I22
J 0
(-6375 4750);
DISPLAY 0.872340 (-6375 4750);
PAINT AQUA (-6375 4750);
DISPLAY INVISIBLE (-6375 4750);
FORCEPROP 1 LAST VOLTAGE 0.0V
J 0
(-6495 4707);
DISPLAY 0.340426 (-6495 4707);
PAINT SKYBLUE (-6495 4707);
DISPLAY INVISIBLE (-6495 4707);
FORCEPROP 1 LAST SIZE 1B
J 0
(-6375 4700);
DISPLAY 2.382979 (-6375 4700);
PAINT GREEN (-6375 4700);
DISPLAY INVISIBLE (-6375 4700);
FORCEPROP 1 LAST BODY_TYPE PLUMBING
J 0
(-6495 4707);
DISPLAY 0.340426 (-6495 4707);
PAINT GREEN (-6495 4707);
DISPLAY INVISIBLE (-6495 4707);
FORCEPROP 1 LAST HDL_POWER GND
J 0
(-6450 4900);
PAINT GREEN (-6450 4900);
DISPLAY INVISIBLE (-6450 4900);
FORCEPROP 2 LAST CDS_LIB mstr_symbols
J 0
(-6450 4750);
DISPLAY INVISIBLE (-6450 4750);
FORCEADD TPAD-DIFF-4P-GP..1
(-5975 4550);
FORCEPROP 2 LASTPIN (-5750 4500) $PN 2
J 0
(-5740 4510);
DISPLAY 0.808511 (-5740 4510);
PAINT ORANGE (-5740 4510);
FORCEPROP 2 LASTPIN (-6200 4500) $PN GND2
J 2
(-6210 4510);
DISPLAY 0.808511 (-6210 4510);
PAINT ORANGE (-6210 4510);
FORCEPROP 1 LAST LOCATION T1P11
J 0
(-5950 4665);
DISPLAY 0.617021 (-5950 4665);
PAINT GREEN (-5950 4665);
FORCEPROP 1 LAST VALUE TPAD-DIFF-4P-GP
J 0
(-6050 4420);
DISPLAY 0.617021 (-6050 4420);
PAINT GREEN (-6050 4420);
FORCEPROP 2 LASTPIN (-6200 4600) $PN GND1
J 2
(-6210 4610);
DISPLAY 0.808511 (-6210 4610);
PAINT ORANGE (-6210 4610);
FORCEPROP 2 LASTPIN (-5750 4600) $PN 1
J 0
(-5740 4610);
DISPLAY 0.808511 (-5740 4610);
PAINT ORANGE (-5740 4610);
FORCEPROP 1 LAST PATH I23
J 0
(-5975 4657);
DISPLAY 0.617021 (-5975 4657);
PAINT GREEN (-5975 4657);
DISPLAY INVISIBLE (-5975 4657);
FORCEPROP 1 LAST PART_NUMBER ZZ.00PAD.NW1
J 0
(-5975 4446);
DISPLAY 0.617021 (-5975 4446);
PAINT GREEN (-5975 4446);
DISPLAY INVISIBLE (-5975 4446);
FORCEPROP 1 LAST CDS_LMAN_SYM_OUTLINE -75,100,75,-100
J 0
(-5975 4550);
DISPLAY 0.468085 (-5975 4550);
PAINT GREEN (-5975 4550);
DISPLAY INVISIBLE (-5975 4550);
FORCEPROP 2 LAST CDS_LIB w_hdl
J 0
(-5975 4550);
DISPLAY INVISIBLE (-5975 4550);
FORCEPROP 1 LAST PACK_TYPE DISCRET-GB3
J 0
(-5975 4550);
DISPLAY 0.617021 (-5975 4550);
PAINT GREEN (-5975 4550);
DISPLAY INVISIBLE (-5975 4550);
FORCEPROP 2 LAST SEC 1
J 0
(-5950 4700);
DISPLAY 0.680851 (-5950 4700);
PAINT MONO (-5950 4700);
DISPLAY INVISIBLE (-5950 4700);
FORCEPROP 2 LAST SEC_TYPE DISCRET-GB3
J 0
(-5950 4700);
DISPLAY 1.021277 (-5950 4700);
PAINT ORANGE (-5950 4700);
DISPLAY INVISIBLE (-5950 4700);
FORCEADD TPAD-DIFF-4P-GP..1
(-5975 4150);
FORCEPROP 1 LAST LOCATION T1P12
J 0
(-5950 4265);
DISPLAY 0.617021 (-5950 4265);
PAINT GREEN (-5950 4265);
FORCEPROP 2 LASTPIN (-6200 4200) $PN GND1
J 2
(-6210 4210);
DISPLAY 0.808511 (-6210 4210);
PAINT ORANGE (-6210 4210);
FORCEPROP 2 LASTPIN (-5750 4100) $PN 2
J 0
(-5740 4110);
DISPLAY 0.808511 (-5740 4110);
PAINT ORANGE (-5740 4110);
FORCEPROP 1 LAST VALUE TPAD-DIFF-4P-GP
J 0
(-6050 4020);
DISPLAY 0.617021 (-6050 4020);
PAINT GREEN (-6050 4020);
FORCEPROP 2 LASTPIN (-5750 4200) $PN 1
J 0
(-5740 4210);
DISPLAY 0.808511 (-5740 4210);
PAINT ORANGE (-5740 4210);
FORCEPROP 2 LASTPIN (-6200 4100) $PN GND2
J 2
(-6210 4110);
DISPLAY 0.808511 (-6210 4110);
PAINT ORANGE (-6210 4110);
FORCEPROP 1 LAST PATH I24
J 0
(-5975 4257);
DISPLAY 0.617021 (-5975 4257);
PAINT GREEN (-5975 4257);
DISPLAY INVISIBLE (-5975 4257);
FORCEPROP 1 LAST PART_NUMBER ZZ.00PAD.NW1
J 0
(-5975 4046);
DISPLAY 0.617021 (-5975 4046);
PAINT GREEN (-5975 4046);
DISPLAY INVISIBLE (-5975 4046);
FORCEPROP 1 LAST CDS_LMAN_SYM_OUTLINE -75,100,75,-100
J 0
(-5975 4150);
DISPLAY 0.468085 (-5975 4150);
PAINT GREEN (-5975 4150);
DISPLAY INVISIBLE (-5975 4150);
FORCEPROP 2 LAST CDS_LIB w_hdl
J 0
(-5975 4150);
DISPLAY INVISIBLE (-5975 4150);
FORCEPROP 1 LAST PACK_TYPE DISCRET-GB3
J 0
(-5975 4150);
DISPLAY 0.617021 (-5975 4150);
PAINT GREEN (-5975 4150);
DISPLAY INVISIBLE (-5975 4150);
FORCEPROP 2 LAST SEC 1
J 0
(-5950 4300);
DISPLAY 0.680851 (-5950 4300);
PAINT MONO (-5950 4300);
DISPLAY INVISIBLE (-5950 4300);
FORCEPROP 2 LAST SEC_TYPE DISCRET-GB3
J 0
(-5950 4300);
DISPLAY 1.021277 (-5950 4300);
PAINT ORANGE (-5950 4300);
DISPLAY INVISIBLE (-5950 4300);
FORCEADD GND..1
(-6425 4400);
FORCEPROP 3 LASTPIN (-6425 4450) SIG_NAME GND\g
J 0
(-6415 4460);
DISPLAY 0.659574 (-6415 4460);
PAINT MONO (-6415 4460);
DISPLAY INVISIBLE (-6415 4460);
FORCEPROP 1 LAST PATH I25
J 0
(-6350 4400);
DISPLAY 0.872340 (-6350 4400);
PAINT AQUA (-6350 4400);
DISPLAY INVISIBLE (-6350 4400);
FORCEPROP 1 LAST VOLTAGE 0.0V
J 0
(-6470 4357);
DISPLAY 0.340426 (-6470 4357);
PAINT SKYBLUE (-6470 4357);
DISPLAY INVISIBLE (-6470 4357);
FORCEPROP 1 LAST SIZE 1B
J 0
(-6350 4350);
DISPLAY 2.382979 (-6350 4350);
PAINT GREEN (-6350 4350);
DISPLAY INVISIBLE (-6350 4350);
FORCEPROP 1 LAST BODY_TYPE PLUMBING
J 0
(-6470 4357);
DISPLAY 0.340426 (-6470 4357);
PAINT GREEN (-6470 4357);
DISPLAY INVISIBLE (-6470 4357);
FORCEPROP 1 LAST HDL_POWER GND
J 0
(-6425 4550);
PAINT GREEN (-6425 4550);
DISPLAY INVISIBLE (-6425 4550);
FORCEPROP 2 LAST CDS_LIB mstr_symbols
J 0
(-6425 4400);
DISPLAY INVISIBLE (-6425 4400);
FORCEADD GND..1
(-6425 4000);
FORCEPROP 3 LASTPIN (-6425 4050) SIG_NAME GND\g
J 0
(-6415 4060);
DISPLAY 0.659574 (-6415 4060);
PAINT MONO (-6415 4060);
DISPLAY INVISIBLE (-6415 4060);
FORCEPROP 1 LAST PATH I26
J 0
(-6350 4000);
DISPLAY 0.872340 (-6350 4000);
PAINT AQUA (-6350 4000);
DISPLAY INVISIBLE (-6350 4000);
FORCEPROP 1 LAST VOLTAGE 0.0V
J 0
(-6470 3957);
DISPLAY 0.340426 (-6470 3957);
PAINT SKYBLUE (-6470 3957);
DISPLAY INVISIBLE (-6470 3957);
FORCEPROP 1 LAST SIZE 1B
J 0
(-6350 3950);
DISPLAY 2.382979 (-6350 3950);
PAINT GREEN (-6350 3950);
DISPLAY INVISIBLE (-6350 3950);
FORCEPROP 1 LAST BODY_TYPE PLUMBING
J 0
(-6470 3957);
DISPLAY 0.340426 (-6470 3957);
PAINT GREEN (-6470 3957);
DISPLAY INVISIBLE (-6470 3957);
FORCEPROP 1 LAST HDL_POWER GND
J 0
(-6425 4150);
PAINT GREEN (-6425 4150);
DISPLAY INVISIBLE (-6425 4150);
FORCEPROP 2 LAST CDS_LIB mstr_symbols
J 0
(-6425 4000);
DISPLAY INVISIBLE (-6425 4000);
FORCEADD TPAD-DIFF-4P-GP..1
(-7975 6100);
FORCEPROP 1 LAST VALUE TPAD-DIFF-4P-GP
J 0
(-8050 5970);
DISPLAY 0.617021 (-8050 5970);
PAINT GREEN (-8050 5970);
FORCEPROP 2 LASTPIN (-7750 6150) $PN 1
J 0
(-7740 6160);
DISPLAY 0.808511 (-7740 6160);
PAINT ORANGE (-7740 6160);
FORCEPROP 2 LASTPIN (-8200 6050) $PN GND2
J 2
(-8210 6060);
DISPLAY 0.808511 (-8210 6060);
PAINT ORANGE (-8210 6060);
FORCEPROP 2 LASTPIN (-7750 6050) $PN 2
J 0
(-7740 6060);
DISPLAY 0.808511 (-7740 6060);
PAINT ORANGE (-7740 6060);
FORCEPROP 2 LASTPIN (-8200 6150) $PN GND1
J 2
(-8210 6160);
DISPLAY 0.808511 (-8210 6160);
PAINT ORANGE (-8210 6160);
FORCEPROP 1 LAST LOCATION T1P1
J 0
(-7950 6215);
DISPLAY 0.617021 (-7950 6215);
PAINT GREEN (-7950 6215);
FORCEPROP 1 LAST PART_NUMBER ZZ.00PAD.NW1
J 0
(-7975 5996);
DISPLAY 0.617021 (-7975 5996);
PAINT GREEN (-7975 5996);
DISPLAY INVISIBLE (-7975 5996);
FORCEPROP 1 LAST CDS_LMAN_SYM_OUTLINE -75,100,75,-100
J 0
(-7975 6100);
DISPLAY 0.468085 (-7975 6100);
PAINT GREEN (-7975 6100);
DISPLAY INVISIBLE (-7975 6100);
FORCEPROP 2 LAST CDS_LIB w_hdl
J 0
(-7975 6100);
DISPLAY INVISIBLE (-7975 6100);
FORCEPROP 1 LAST PACK_TYPE DISCRET-GB3
J 0
(-7975 6100);
DISPLAY 0.617021 (-7975 6100);
PAINT GREEN (-7975 6100);
DISPLAY INVISIBLE (-7975 6100);
FORCEPROP 2 LAST SEC 1
J 0
(-7950 6250);
DISPLAY 0.680851 (-7950 6250);
PAINT MONO (-7950 6250);
DISPLAY INVISIBLE (-7950 6250);
FORCEPROP 2 LAST SEC_TYPE DISCRET-GB3
J 0
(-7950 6250);
DISPLAY 1.021277 (-7950 6250);
PAINT ORANGE (-7950 6250);
DISPLAY INVISIBLE (-7950 6250);
FORCEPROP 1 LAST PATH I3
J 0
(-7975 6207);
DISPLAY 0.617021 (-7975 6207);
PAINT GREEN (-7975 6207);
DISPLAY INVISIBLE (-7975 6207);
FORCEADD TPAD-DIFF-4P-GP..1
(-4200 5675);
FORCEPROP 2 LASTPIN (-3975 5725) $PN 1
J 0
(-3965 5735);
DISPLAY 0.808511 (-3965 5735);
PAINT ORANGE (-3965 5735);
FORCEPROP 2 LASTPIN (-3975 5625) $PN 2
J 0
(-3965 5635);
DISPLAY 0.808511 (-3965 5635);
PAINT ORANGE (-3965 5635);
FORCEPROP 1 LAST LOCATION T1P14
J 0
(-4175 5790);
DISPLAY 0.617021 (-4175 5790);
PAINT GREEN (-4175 5790);
FORCEPROP 1 LAST VALUE TPAD-DIFF-4P-GP
J 0
(-4275 5545);
DISPLAY 0.617021 (-4275 5545);
PAINT GREEN (-4275 5545);
FORCEPROP 2 LASTPIN (-4425 5625) $PN GND2
J 2
(-4435 5635);
DISPLAY 0.808511 (-4435 5635);
PAINT ORANGE (-4435 5635);
FORCEPROP 2 LASTPIN (-4425 5725) $PN GND1
J 2
(-4435 5735);
DISPLAY 0.808511 (-4435 5735);
PAINT ORANGE (-4435 5735);
FORCEPROP 1 LAST PART_NUMBER ZZ.00PAD.NW1
J 0
(-4200 5571);
DISPLAY 0.617021 (-4200 5571);
PAINT GREEN (-4200 5571);
DISPLAY INVISIBLE (-4200 5571);
FORCEPROP 1 LAST CDS_LMAN_SYM_OUTLINE -75,100,75,-100
J 0
(-4200 5675);
DISPLAY 0.468085 (-4200 5675);
PAINT GREEN (-4200 5675);
DISPLAY INVISIBLE (-4200 5675);
FORCEPROP 2 LAST CDS_LIB w_hdl
J 0
(-4200 5675);
DISPLAY INVISIBLE (-4200 5675);
FORCEPROP 1 LAST PACK_TYPE DISCRET-GB3
J 0
(-4200 5675);
DISPLAY 0.617021 (-4200 5675);
PAINT GREEN (-4200 5675);
DISPLAY INVISIBLE (-4200 5675);
FORCEPROP 2 LAST SEC 1
J 0
(-4175 5825);
DISPLAY 0.680851 (-4175 5825);
PAINT MONO (-4175 5825);
DISPLAY INVISIBLE (-4175 5825);
FORCEPROP 2 LAST SEC_TYPE DISCRET-GB3
J 0
(-4175 5825);
DISPLAY 1.021277 (-4175 5825);
PAINT ORANGE (-4175 5825);
DISPLAY INVISIBLE (-4175 5825);
FORCEPROP 1 LAST PATH I30
J 0
(-4200 5782);
DISPLAY 0.617021 (-4200 5782);
PAINT GREEN (-4200 5782);
DISPLAY INVISIBLE (-4200 5782);
FORCEADD GND..1
(-4650 5525);
FORCEPROP 3 LASTPIN (-4650 5575) SIG_NAME GND\g
J 0
(-4640 5585);
DISPLAY 0.659574 (-4640 5585);
PAINT MONO (-4640 5585);
DISPLAY INVISIBLE (-4640 5585);
FORCEPROP 1 LAST VOLTAGE 0.0V
J 0
(-4695 5482);
DISPLAY 0.340426 (-4695 5482);
PAINT SKYBLUE (-4695 5482);
DISPLAY INVISIBLE (-4695 5482);
FORCEPROP 1 LAST SIZE 1B
J 0
(-4575 5475);
DISPLAY 2.382979 (-4575 5475);
PAINT GREEN (-4575 5475);
DISPLAY INVISIBLE (-4575 5475);
FORCEPROP 1 LAST BODY_TYPE PLUMBING
J 0
(-4695 5482);
DISPLAY 0.340426 (-4695 5482);
PAINT GREEN (-4695 5482);
DISPLAY INVISIBLE (-4695 5482);
FORCEPROP 1 LAST HDL_POWER GND
J 0
(-4650 5675);
PAINT GREEN (-4650 5675);
DISPLAY INVISIBLE (-4650 5675);
FORCEPROP 2 LAST CDS_LIB mstr_symbols
J 0
(-4650 5525);
DISPLAY INVISIBLE (-4650 5525);
FORCEPROP 1 LAST PATH I32
J 0
(-4575 5525);
DISPLAY 0.872340 (-4575 5525);
PAINT AQUA (-4575 5525);
DISPLAY INVISIBLE (-4575 5525);
FORCEADD TPAD-DIFF-4P-GP..1
(-4175 4550);
FORCEPROP 2 LASTPIN (-4400 4500) $PN GND2
J 2
(-4410 4510);
DISPLAY 0.808511 (-4410 4510);
PAINT ORANGE (-4410 4510);
FORCEPROP 2 LASTPIN (-4400 4600) $PN GND1
J 2
(-4410 4610);
DISPLAY 0.808511 (-4410 4610);
PAINT ORANGE (-4410 4610);
FORCEPROP 1 LAST LOCATION T1P17
J 0
(-4150 4665);
DISPLAY 0.617021 (-4150 4665);
PAINT GREEN (-4150 4665);
FORCEPROP 1 LAST VALUE TPAD-DIFF-4P-GP
J 0
(-4250 4420);
DISPLAY 0.617021 (-4250 4420);
PAINT GREEN (-4250 4420);
FORCEPROP 2 LASTPIN (-3950 4500) $PN 2
J 0
(-3940 4510);
DISPLAY 0.808511 (-3940 4510);
PAINT ORANGE (-3940 4510);
FORCEPROP 2 LASTPIN (-3950 4600) $PN 1
J 0
(-3940 4610);
DISPLAY 0.808511 (-3940 4610);
PAINT ORANGE (-3940 4610);
FORCEPROP 1 LAST PART_NUMBER ZZ.00PAD.NW1
J 0
(-4175 4446);
DISPLAY 0.617021 (-4175 4446);
PAINT GREEN (-4175 4446);
DISPLAY INVISIBLE (-4175 4446);
FORCEPROP 1 LAST CDS_LMAN_SYM_OUTLINE -75,100,75,-100
J 0
(-4175 4550);
DISPLAY 0.468085 (-4175 4550);
PAINT GREEN (-4175 4550);
DISPLAY INVISIBLE (-4175 4550);
FORCEPROP 2 LAST CDS_LIB w_hdl
J 0
(-4175 4550);
DISPLAY INVISIBLE (-4175 4550);
FORCEPROP 1 LAST PACK_TYPE DISCRET-GB3
J 0
(-4175 4550);
DISPLAY 0.617021 (-4175 4550);
PAINT GREEN (-4175 4550);
DISPLAY INVISIBLE (-4175 4550);
FORCEPROP 2 LAST SEC 1
J 0
(-4150 4700);
DISPLAY 0.680851 (-4150 4700);
PAINT MONO (-4150 4700);
DISPLAY INVISIBLE (-4150 4700);
FORCEPROP 2 LAST SEC_TYPE DISCRET-GB3
J 0
(-4150 4700);
DISPLAY 1.021277 (-4150 4700);
PAINT ORANGE (-4150 4700);
DISPLAY INVISIBLE (-4150 4700);
FORCEPROP 1 LAST PATH I36
J 0
(-4175 4657);
DISPLAY 0.617021 (-4175 4657);
PAINT GREEN (-4175 4657);
DISPLAY INVISIBLE (-4175 4657);
FORCEADD GND..1
(-4625 4400);
FORCEPROP 3 LASTPIN (-4625 4450) SIG_NAME GND\g
J 0
(-4615 4460);
DISPLAY 0.659574 (-4615 4460);
PAINT MONO (-4615 4460);
DISPLAY INVISIBLE (-4615 4460);
FORCEPROP 1 LAST VOLTAGE 0.0V
J 0
(-4670 4357);
DISPLAY 0.340426 (-4670 4357);
PAINT SKYBLUE (-4670 4357);
DISPLAY INVISIBLE (-4670 4357);
FORCEPROP 1 LAST SIZE 1B
J 0
(-4550 4350);
DISPLAY 2.382979 (-4550 4350);
PAINT GREEN (-4550 4350);
DISPLAY INVISIBLE (-4550 4350);
FORCEPROP 1 LAST BODY_TYPE PLUMBING
J 0
(-4670 4357);
DISPLAY 0.340426 (-4670 4357);
PAINT GREEN (-4670 4357);
DISPLAY INVISIBLE (-4670 4357);
FORCEPROP 1 LAST HDL_POWER GND
J 0
(-4625 4550);
PAINT GREEN (-4625 4550);
DISPLAY INVISIBLE (-4625 4550);
FORCEPROP 2 LAST CDS_LIB mstr_symbols
J 0
(-4625 4400);
DISPLAY INVISIBLE (-4625 4400);
FORCEPROP 1 LAST PATH I37
J 0
(-4550 4400);
DISPLAY 0.872340 (-4550 4400);
PAINT AQUA (-4550 4400);
DISPLAY INVISIBLE (-4550 4400);
FORCEADD TPAD-DIFF-4P-GP..1
(-2375 4200);
FORCEPROP 2 LASTPIN (-2150 4250) $PN 1
J 0
(-2140 4260);
DISPLAY 0.808511 (-2140 4260);
PAINT ORANGE (-2140 4260);
FORCEPROP 2 LASTPIN (-2600 4150) $PN GND2
J 2
(-2610 4160);
DISPLAY 0.808511 (-2610 4160);
PAINT ORANGE (-2610 4160);
FORCEPROP 2 LASTPIN (-2150 4150) $PN 2
J 0
(-2140 4160);
DISPLAY 0.808511 (-2140 4160);
PAINT ORANGE (-2140 4160);
FORCEPROP 1 LAST LOCATION T1P24
J 0
(-2350 4315);
DISPLAY 0.617021 (-2350 4315);
PAINT GREEN (-2350 4315);
FORCEPROP 1 LAST VALUE TPAD-DIFF-4P-GP
J 0
(-2450 4070);
DISPLAY 0.617021 (-2450 4070);
PAINT GREEN (-2450 4070);
FORCEPROP 2 LASTPIN (-2600 4250) $PN GND1
J 2
(-2610 4260);
DISPLAY 0.808511 (-2610 4260);
PAINT ORANGE (-2610 4260);
FORCEPROP 1 LAST PART_NUMBER ZZ.00PAD.NW1
J 0
(-2375 4096);
DISPLAY 0.617021 (-2375 4096);
PAINT GREEN (-2375 4096);
DISPLAY INVISIBLE (-2375 4096);
FORCEPROP 1 LAST CDS_LMAN_SYM_OUTLINE -75,100,75,-100
J 0
(-2375 4200);
DISPLAY 0.468085 (-2375 4200);
PAINT GREEN (-2375 4200);
DISPLAY INVISIBLE (-2375 4200);
FORCEPROP 2 LAST CDS_LIB w_hdl
J 0
(-2375 4200);
DISPLAY INVISIBLE (-2375 4200);
FORCEPROP 1 LAST PACK_TYPE DISCRET-GB3
J 0
(-2375 4200);
DISPLAY 0.617021 (-2375 4200);
PAINT GREEN (-2375 4200);
DISPLAY INVISIBLE (-2375 4200);
FORCEPROP 2 LAST SEC 1
J 0
(-2350 4350);
DISPLAY 0.680851 (-2350 4350);
PAINT MONO (-2350 4350);
DISPLAY INVISIBLE (-2350 4350);
FORCEPROP 2 LAST SEC_TYPE DISCRET-GB3
J 0
(-2350 4350);
DISPLAY 1.021277 (-2350 4350);
PAINT ORANGE (-2350 4350);
DISPLAY INVISIBLE (-2350 4350);
FORCEPROP 1 LAST PATH I38
J 0
(-2375 4307);
DISPLAY 0.617021 (-2375 4307);
PAINT GREEN (-2375 4307);
DISPLAY INVISIBLE (-2375 4307);
FORCEADD TPAD-DIFF-4P-GP..1
(-2400 6125);
FORCEPROP 2 LASTPIN (-2625 6075) $PN GND2
J 2
(-2635 6085);
DISPLAY 0.808511 (-2635 6085);
PAINT ORANGE (-2635 6085);
FORCEPROP 2 LASTPIN (-2625 6175) $PN GND1
J 2
(-2635 6185);
DISPLAY 0.808511 (-2635 6185);
PAINT ORANGE (-2635 6185);
FORCEPROP 2 LASTPIN (-2175 6175) $PN 1
J 0
(-2165 6185);
DISPLAY 0.808511 (-2165 6185);
PAINT ORANGE (-2165 6185);
FORCEPROP 2 LASTPIN (-2175 6075) $PN 2
J 0
(-2165 6085);
DISPLAY 0.808511 (-2165 6085);
PAINT ORANGE (-2165 6085);
FORCEPROP 1 LAST LOCATION T1P19
J 0
(-2375 6240);
DISPLAY 0.617021 (-2375 6240);
PAINT GREEN (-2375 6240);
FORCEPROP 1 LAST VALUE TPAD-DIFF-4P-GP
J 0
(-2475 5995);
DISPLAY 0.617021 (-2475 5995);
PAINT GREEN (-2475 5995);
FORCEPROP 1 LAST PART_NUMBER ZZ.00PAD.NW1
J 0
(-2400 6021);
DISPLAY 0.617021 (-2400 6021);
PAINT GREEN (-2400 6021);
DISPLAY INVISIBLE (-2400 6021);
FORCEPROP 1 LAST CDS_LMAN_SYM_OUTLINE -75,100,75,-100
J 0
(-2400 6125);
DISPLAY 0.468085 (-2400 6125);
PAINT GREEN (-2400 6125);
DISPLAY INVISIBLE (-2400 6125);
FORCEPROP 2 LAST CDS_LIB w_hdl
J 0
(-2400 6125);
DISPLAY INVISIBLE (-2400 6125);
FORCEPROP 1 LAST PACK_TYPE DISCRET-GB3
J 0
(-2400 6125);
DISPLAY 0.617021 (-2400 6125);
PAINT GREEN (-2400 6125);
DISPLAY INVISIBLE (-2400 6125);
FORCEPROP 2 LAST SEC 1
J 0
(-2375 6275);
DISPLAY 0.680851 (-2375 6275);
PAINT MONO (-2375 6275);
DISPLAY INVISIBLE (-2375 6275);
FORCEPROP 2 LAST SEC_TYPE DISCRET-GB3
J 0
(-2375 6275);
DISPLAY 1.021277 (-2375 6275);
PAINT ORANGE (-2375 6275);
DISPLAY INVISIBLE (-2375 6275);
FORCEPROP 1 LAST PATH I39
J 0
(-2400 6232);
DISPLAY 0.617021 (-2400 6232);
PAINT GREEN (-2400 6232);
DISPLAY INVISIBLE (-2400 6232);
FORCEADD GND..1
(-8425 5950);
FORCEPROP 3 LASTPIN (-8425 6000) SIG_NAME GND\g
J 0
(-8415 6010);
DISPLAY 0.659574 (-8415 6010);
PAINT MONO (-8415 6010);
DISPLAY INVISIBLE (-8415 6010);
FORCEPROP 1 LAST VOLTAGE 0.0V
J 0
(-8470 5907);
DISPLAY 0.340426 (-8470 5907);
PAINT SKYBLUE (-8470 5907);
DISPLAY INVISIBLE (-8470 5907);
FORCEPROP 1 LAST SIZE 1B
J 0
(-8350 5900);
DISPLAY 2.382979 (-8350 5900);
PAINT GREEN (-8350 5900);
DISPLAY INVISIBLE (-8350 5900);
FORCEPROP 1 LAST BODY_TYPE PLUMBING
J 0
(-8470 5907);
DISPLAY 0.340426 (-8470 5907);
PAINT GREEN (-8470 5907);
DISPLAY INVISIBLE (-8470 5907);
FORCEPROP 1 LAST HDL_POWER GND
J 0
(-8425 6100);
PAINT GREEN (-8425 6100);
DISPLAY INVISIBLE (-8425 6100);
FORCEPROP 1 LAST PATH I4
J 0
(-8350 5950);
DISPLAY 0.872340 (-8350 5950);
PAINT AQUA (-8350 5950);
DISPLAY INVISIBLE (-8350 5950);
FORCEPROP 2 LAST CDS_LIB mstr_symbols
J 0
(-8425 5950);
DISPLAY INVISIBLE (-8425 5950);
FORCEADD GND..1
(-2850 5975);
FORCEPROP 3 LASTPIN (-2850 6025) SIG_NAME GND\g
J 0
(-2840 6035);
DISPLAY 0.659574 (-2840 6035);
PAINT MONO (-2840 6035);
DISPLAY INVISIBLE (-2840 6035);
FORCEPROP 1 LAST VOLTAGE 0.0V
J 0
(-2895 5932);
DISPLAY 0.340426 (-2895 5932);
PAINT SKYBLUE (-2895 5932);
DISPLAY INVISIBLE (-2895 5932);
FORCEPROP 1 LAST SIZE 1B
J 0
(-2775 5925);
DISPLAY 2.382979 (-2775 5925);
PAINT GREEN (-2775 5925);
DISPLAY INVISIBLE (-2775 5925);
FORCEPROP 1 LAST BODY_TYPE PLUMBING
J 0
(-2895 5932);
DISPLAY 0.340426 (-2895 5932);
PAINT GREEN (-2895 5932);
DISPLAY INVISIBLE (-2895 5932);
FORCEPROP 1 LAST HDL_POWER GND
J 0
(-2850 6125);
PAINT GREEN (-2850 6125);
DISPLAY INVISIBLE (-2850 6125);
FORCEPROP 2 LAST CDS_LIB mstr_symbols
J 0
(-2850 5975);
DISPLAY INVISIBLE (-2850 5975);
FORCEPROP 1 LAST PATH I40
J 0
(-2775 5975);
DISPLAY 0.872340 (-2775 5975);
PAINT AQUA (-2775 5975);
DISPLAY INVISIBLE (-2775 5975);
FORCEADD TPAD-DIFF-4P-GP..1
(-2400 4950);
FORCEPROP 1 LAST LOCATION T1P22
J 0
(-2375 5065);
DISPLAY 0.617021 (-2375 5065);
PAINT GREEN (-2375 5065);
FORCEPROP 2 LASTPIN (-2175 4900) $PN 2
J 0
(-2165 4910);
DISPLAY 0.808511 (-2165 4910);
PAINT ORANGE (-2165 4910);
FORCEPROP 1 LAST VALUE TPAD-DIFF-4P-GP
J 0
(-2475 4820);
DISPLAY 0.617021 (-2475 4820);
PAINT GREEN (-2475 4820);
FORCEPROP 2 LASTPIN (-2175 5000) $PN 1
J 0
(-2165 5010);
DISPLAY 0.808511 (-2165 5010);
PAINT ORANGE (-2165 5010);
FORCEPROP 2 LASTPIN (-2625 5000) $PN GND1
J 2
(-2635 5010);
DISPLAY 0.808511 (-2635 5010);
PAINT ORANGE (-2635 5010);
FORCEPROP 2 LASTPIN (-2625 4900) $PN GND2
J 2
(-2635 4910);
DISPLAY 0.808511 (-2635 4910);
PAINT ORANGE (-2635 4910);
FORCEPROP 1 LAST PART_NUMBER ZZ.00PAD.NW1
J 0
(-2400 4846);
DISPLAY 0.617021 (-2400 4846);
PAINT GREEN (-2400 4846);
DISPLAY INVISIBLE (-2400 4846);
FORCEPROP 1 LAST CDS_LMAN_SYM_OUTLINE -75,100,75,-100
J 0
(-2400 4950);
DISPLAY 0.468085 (-2400 4950);
PAINT GREEN (-2400 4950);
DISPLAY INVISIBLE (-2400 4950);
FORCEPROP 2 LAST CDS_LIB w_hdl
J 0
(-2400 4950);
DISPLAY INVISIBLE (-2400 4950);
FORCEPROP 1 LAST PACK_TYPE DISCRET-GB3
J 0
(-2400 4950);
DISPLAY 0.617021 (-2400 4950);
PAINT GREEN (-2400 4950);
DISPLAY INVISIBLE (-2400 4950);
FORCEPROP 2 LAST SEC 1
J 0
(-2375 5100);
DISPLAY 0.680851 (-2375 5100);
PAINT MONO (-2375 5100);
DISPLAY INVISIBLE (-2375 5100);
FORCEPROP 2 LAST SEC_TYPE DISCRET-GB3
J 0
(-2375 5100);
DISPLAY 1.021277 (-2375 5100);
PAINT ORANGE (-2375 5100);
DISPLAY INVISIBLE (-2375 5100);
FORCEPROP 1 LAST PATH I45
J 0
(-2400 5057);
DISPLAY 0.617021 (-2400 5057);
PAINT GREEN (-2400 5057);
DISPLAY INVISIBLE (-2400 5057);
FORCEADD GND..1
(-2850 4800);
FORCEPROP 3 LASTPIN (-2850 4850) SIG_NAME GND\g
J 0
(-2840 4860);
DISPLAY 0.659574 (-2840 4860);
PAINT MONO (-2840 4860);
DISPLAY INVISIBLE (-2840 4860);
FORCEPROP 1 LAST VOLTAGE 0.0V
J 0
(-2895 4757);
DISPLAY 0.340426 (-2895 4757);
PAINT SKYBLUE (-2895 4757);
DISPLAY INVISIBLE (-2895 4757);
FORCEPROP 1 LAST SIZE 1B
J 0
(-2775 4750);
DISPLAY 2.382979 (-2775 4750);
PAINT GREEN (-2775 4750);
DISPLAY INVISIBLE (-2775 4750);
FORCEPROP 1 LAST BODY_TYPE PLUMBING
J 0
(-2895 4757);
DISPLAY 0.340426 (-2895 4757);
PAINT GREEN (-2895 4757);
DISPLAY INVISIBLE (-2895 4757);
FORCEPROP 1 LAST HDL_POWER GND
J 0
(-2850 4950);
PAINT GREEN (-2850 4950);
DISPLAY INVISIBLE (-2850 4950);
FORCEPROP 2 LAST CDS_LIB mstr_symbols
J 0
(-2850 4800);
DISPLAY INVISIBLE (-2850 4800);
FORCEPROP 1 LAST PATH I46
J 0
(-2775 4800);
DISPLAY 0.872340 (-2775 4800);
PAINT AQUA (-2775 4800);
DISPLAY INVISIBLE (-2775 4800);
FORCEADD TPAD-DIFF-4P-GP..1
(-2375 4600);
FORCEPROP 2 LASTPIN (-2600 4550) $PN GND2
J 2
(-2610 4560);
DISPLAY 0.808511 (-2610 4560);
PAINT ORANGE (-2610 4560);
FORCEPROP 1 LAST VALUE TPAD-DIFF-4P-GP
J 0
(-2450 4470);
DISPLAY 0.617021 (-2450 4470);
PAINT GREEN (-2450 4470);
FORCEPROP 2 LASTPIN (-2150 4650) $PN 1
J 0
(-2140 4660);
DISPLAY 0.808511 (-2140 4660);
PAINT ORANGE (-2140 4660);
FORCEPROP 2 LASTPIN (-2150 4550) $PN 2
J 0
(-2140 4560);
DISPLAY 0.808511 (-2140 4560);
PAINT ORANGE (-2140 4560);
FORCEPROP 1 LAST LOCATION T1P23
J 0
(-2350 4715);
DISPLAY 0.617021 (-2350 4715);
PAINT GREEN (-2350 4715);
FORCEPROP 2 LASTPIN (-2600 4650) $PN GND1
J 2
(-2610 4660);
DISPLAY 0.808511 (-2610 4660);
PAINT ORANGE (-2610 4660);
FORCEPROP 1 LAST PART_NUMBER ZZ.00PAD.NW1
J 0
(-2375 4496);
DISPLAY 0.617021 (-2375 4496);
PAINT GREEN (-2375 4496);
DISPLAY INVISIBLE (-2375 4496);
FORCEPROP 1 LAST CDS_LMAN_SYM_OUTLINE -75,100,75,-100
J 0
(-2375 4600);
DISPLAY 0.468085 (-2375 4600);
PAINT GREEN (-2375 4600);
DISPLAY INVISIBLE (-2375 4600);
FORCEPROP 2 LAST CDS_LIB w_hdl
J 0
(-2375 4600);
DISPLAY INVISIBLE (-2375 4600);
FORCEPROP 1 LAST PACK_TYPE DISCRET-GB3
J 0
(-2375 4600);
DISPLAY 0.617021 (-2375 4600);
PAINT GREEN (-2375 4600);
DISPLAY INVISIBLE (-2375 4600);
FORCEPROP 2 LAST SEC 1
J 0
(-2350 4750);
DISPLAY 0.680851 (-2350 4750);
PAINT MONO (-2350 4750);
DISPLAY INVISIBLE (-2350 4750);
FORCEPROP 2 LAST SEC_TYPE DISCRET-GB3
J 0
(-2350 4750);
DISPLAY 1.021277 (-2350 4750);
PAINT ORANGE (-2350 4750);
DISPLAY INVISIBLE (-2350 4750);
FORCEPROP 1 LAST PATH I47
J 0
(-2375 4707);
DISPLAY 0.617021 (-2375 4707);
PAINT GREEN (-2375 4707);
DISPLAY INVISIBLE (-2375 4707);
FORCEADD GND..1
(-2825 4450);
FORCEPROP 3 LASTPIN (-2825 4500) SIG_NAME GND\g
J 0
(-2815 4510);
DISPLAY 0.659574 (-2815 4510);
PAINT MONO (-2815 4510);
DISPLAY INVISIBLE (-2815 4510);
FORCEPROP 1 LAST VOLTAGE 0.0V
J 0
(-2870 4407);
DISPLAY 0.340426 (-2870 4407);
PAINT SKYBLUE (-2870 4407);
DISPLAY INVISIBLE (-2870 4407);
FORCEPROP 1 LAST SIZE 1B
J 0
(-2750 4400);
DISPLAY 2.382979 (-2750 4400);
PAINT GREEN (-2750 4400);
DISPLAY INVISIBLE (-2750 4400);
FORCEPROP 1 LAST BODY_TYPE PLUMBING
J 0
(-2870 4407);
DISPLAY 0.340426 (-2870 4407);
PAINT GREEN (-2870 4407);
DISPLAY INVISIBLE (-2870 4407);
FORCEPROP 1 LAST HDL_POWER GND
J 0
(-2825 4600);
PAINT GREEN (-2825 4600);
DISPLAY INVISIBLE (-2825 4600);
FORCEPROP 2 LAST CDS_LIB mstr_symbols
J 0
(-2825 4450);
DISPLAY INVISIBLE (-2825 4450);
FORCEPROP 1 LAST PATH I48
J 0
(-2750 4450);
DISPLAY 0.872340 (-2750 4450);
PAINT AQUA (-2750 4450);
DISPLAY INVISIBLE (-2750 4450);
FORCEADD GND..1
(-2825 4050);
FORCEPROP 3 LASTPIN (-2825 4100) SIG_NAME GND\g
J 0
(-2815 4110);
DISPLAY 0.659574 (-2815 4110);
PAINT MONO (-2815 4110);
DISPLAY INVISIBLE (-2815 4110);
FORCEPROP 1 LAST VOLTAGE 0.0V
J 0
(-2870 4007);
DISPLAY 0.340426 (-2870 4007);
PAINT SKYBLUE (-2870 4007);
DISPLAY INVISIBLE (-2870 4007);
FORCEPROP 1 LAST SIZE 1B
J 0
(-2750 4000);
DISPLAY 2.382979 (-2750 4000);
PAINT GREEN (-2750 4000);
DISPLAY INVISIBLE (-2750 4000);
FORCEPROP 1 LAST BODY_TYPE PLUMBING
J 0
(-2870 4007);
DISPLAY 0.340426 (-2870 4007);
PAINT GREEN (-2870 4007);
DISPLAY INVISIBLE (-2870 4007);
FORCEPROP 1 LAST HDL_POWER GND
J 0
(-2825 4200);
PAINT GREEN (-2825 4200);
DISPLAY INVISIBLE (-2825 4200);
FORCEPROP 2 LAST CDS_LIB mstr_symbols
J 0
(-2825 4050);
DISPLAY INVISIBLE (-2825 4050);
FORCEPROP 1 LAST PATH I49
J 0
(-2750 4050);
DISPLAY 0.872340 (-2750 4050);
PAINT AQUA (-2750 4050);
DISPLAY INVISIBLE (-2750 4050);
FORCEADD TPAD-DIFF-4P-GP..1
(-7975 5700);
FORCEPROP 1 LAST LOCATION T1P2
J 0
(-7950 5815);
DISPLAY 0.617021 (-7950 5815);
PAINT GREEN (-7950 5815);
FORCEPROP 2 LASTPIN (-7750 5750) $PN 1
J 0
(-7740 5760);
DISPLAY 0.808511 (-7740 5760);
PAINT ORANGE (-7740 5760);
FORCEPROP 2 LASTPIN (-8200 5650) $PN GND2
J 2
(-8210 5660);
DISPLAY 0.808511 (-8210 5660);
PAINT ORANGE (-8210 5660);
FORCEPROP 2 LASTPIN (-8200 5750) $PN GND1
J 2
(-8210 5760);
DISPLAY 0.808511 (-8210 5760);
PAINT ORANGE (-8210 5760);
FORCEPROP 2 LASTPIN (-7750 5650) $PN 2
J 0
(-7740 5660);
DISPLAY 0.808511 (-7740 5660);
PAINT ORANGE (-7740 5660);
FORCEPROP 1 LAST VALUE TPAD-DIFF-4P-GP
J 0
(-8050 5570);
DISPLAY 0.617021 (-8050 5570);
PAINT GREEN (-8050 5570);
FORCEPROP 1 LAST PATH I5
J 0
(-7975 5807);
DISPLAY 0.617021 (-7975 5807);
PAINT GREEN (-7975 5807);
DISPLAY INVISIBLE (-7975 5807);
FORCEPROP 1 LAST PART_NUMBER ZZ.00PAD.NW1
J 0
(-7975 5596);
DISPLAY 0.617021 (-7975 5596);
PAINT GREEN (-7975 5596);
DISPLAY INVISIBLE (-7975 5596);
FORCEPROP 1 LAST CDS_LMAN_SYM_OUTLINE -75,100,75,-100
J 0
(-7975 5700);
DISPLAY 0.468085 (-7975 5700);
PAINT GREEN (-7975 5700);
DISPLAY INVISIBLE (-7975 5700);
FORCEPROP 2 LAST CDS_LIB w_hdl
J 0
(-7975 5700);
DISPLAY INVISIBLE (-7975 5700);
FORCEPROP 1 LAST PACK_TYPE DISCRET-GB3
J 0
(-7975 5700);
DISPLAY 0.617021 (-7975 5700);
PAINT GREEN (-7975 5700);
DISPLAY INVISIBLE (-7975 5700);
FORCEPROP 2 LAST SEC 1
J 0
(-7950 5850);
DISPLAY 0.680851 (-7950 5850);
PAINT MONO (-7950 5850);
DISPLAY INVISIBLE (-7950 5850);
FORCEPROP 2 LAST SEC_TYPE DISCRET-GB3
J 0
(-7950 5850);
DISPLAY 1.021277 (-7950 5850);
PAINT ORANGE (-7950 5850);
DISPLAY INVISIBLE (-7950 5850);
FORCEADD TPAD-SE-2P-GP..1
R 2
(-8300 3500);
FORCEPROP 1 LAST LOCATION T1P25
J 2
(-8325 3615);
DISPLAY 0.617021 (-8325 3615);
PAINT GREEN (-8325 3615);
FORCEPROP 1 LAST VALUE TPAD-SE-2P-GP
J 2
(-8225 3365);
DISPLAY 0.617021 (-8225 3365);
PAINT GREEN (-8225 3365);
FORCEPROP 1 LAST PATH I50
J 2
(-8300 3540);
DISPLAY 0.617021 (-8300 3540);
PAINT GREEN (-8300 3540);
DISPLAY INVISIBLE (-8300 3540);
FORCEPROP 1 LAST PACK_TYPE DISCRET-GA1
J 2
(-8300 3500);
DISPLAY 0.617021 (-8300 3500);
PAINT GREEN (-8300 3500);
DISPLAY INVISIBLE (-8300 3500);
FORCEPROP 1 LAST PART_NUMBER ZZ.00PAD.NU1
J 2
(-8300 3461);
DISPLAY 0.617021 (-8300 3461);
PAINT GREEN (-8300 3461);
DISPLAY INVISIBLE (-8300 3461);
FORCEPROP 2 LAST CDS_LIB w_hdl
J 2
(-8300 3500);
DISPLAY INVISIBLE (-8300 3500);
FORCEPROP 1 LAST CDS_LMAN_SYM_OUTLINE -75,100,75,-100
J 2
(-8300 3500);
DISPLAY 0.468085 (-8300 3500);
PAINT GREEN (-8300 3500);
DISPLAY INVISIBLE (-8300 3500);
FORCEADD GND..1
(-8000 3300);
FORCEPROP 3 LASTPIN (-8000 3350) SIG_NAME GND\g
J 0
(-7990 3360);
DISPLAY 0.659574 (-7990 3360);
PAINT MONO (-7990 3360);
DISPLAY INVISIBLE (-7990 3360);
FORCEPROP 1 LAST PATH I51
J 0
(-7925 3300);
DISPLAY 0.872340 (-7925 3300);
PAINT AQUA (-7925 3300);
DISPLAY INVISIBLE (-7925 3300);
FORCEPROP 1 LAST VOLTAGE 0.0V
J 0
(-8045 3257);
DISPLAY 0.340426 (-8045 3257);
PAINT SKYBLUE (-8045 3257);
DISPLAY INVISIBLE (-8045 3257);
FORCEPROP 1 LAST SIZE 1B
J 0
(-7925 3250);
DISPLAY 2.382979 (-7925 3250);
PAINT GREEN (-7925 3250);
DISPLAY INVISIBLE (-7925 3250);
FORCEPROP 1 LAST BODY_TYPE PLUMBING
J 0
(-8045 3257);
DISPLAY 0.340426 (-8045 3257);
PAINT GREEN (-8045 3257);
DISPLAY INVISIBLE (-8045 3257);
FORCEPROP 1 LAST HDL_POWER GND
J 0
(-8000 3450);
PAINT GREEN (-8000 3450);
DISPLAY INVISIBLE (-8000 3450);
FORCEPROP 2 LAST CDS_LIB mstr_symbols
J 0
(-8000 3300);
DISPLAY INVISIBLE (-8000 3300);
FORCEADD TPAD-SE-2P-GP..1
R 2
(-8300 3100);
FORCEPROP 1 LAST VALUE TPAD-SE-2P-GP
J 2
(-8225 2965);
DISPLAY 0.617021 (-8225 2965);
PAINT GREEN (-8225 2965);
FORCEPROP 1 LAST LOCATION T1P26
J 2
(-8325 3215);
DISPLAY 0.617021 (-8325 3215);
PAINT GREEN (-8325 3215);
FORCEPROP 1 LAST PATH I52
J 2
(-8300 3140);
DISPLAY 0.617021 (-8300 3140);
PAINT GREEN (-8300 3140);
DISPLAY INVISIBLE (-8300 3140);
FORCEPROP 1 LAST PACK_TYPE DISCRET-GA1
J 2
(-8300 3100);
DISPLAY 0.617021 (-8300 3100);
PAINT GREEN (-8300 3100);
DISPLAY INVISIBLE (-8300 3100);
FORCEPROP 1 LAST PART_NUMBER ZZ.00PAD.NU1
J 2
(-8300 3061);
DISPLAY 0.617021 (-8300 3061);
PAINT GREEN (-8300 3061);
DISPLAY INVISIBLE (-8300 3061);
FORCEPROP 1 LAST CDS_LMAN_SYM_OUTLINE -75,100,75,-100
J 2
(-8300 3100);
DISPLAY 0.468085 (-8300 3100);
PAINT GREEN (-8300 3100);
DISPLAY INVISIBLE (-8300 3100);
FORCEPROP 2 LAST CDS_LIB w_hdl
J 0
(-8300 3100);
DISPLAY INVISIBLE (-8300 3100);
FORCEADD GND..1
(-8000 2900);
FORCEPROP 3 LASTPIN (-8000 2950) SIG_NAME GND\g
J 0
(-7990 2960);
DISPLAY 0.659574 (-7990 2960);
PAINT MONO (-7990 2960);
DISPLAY INVISIBLE (-7990 2960);
FORCEPROP 1 LAST PATH I53
J 0
(-7925 2900);
DISPLAY 0.872340 (-7925 2900);
PAINT AQUA (-7925 2900);
DISPLAY INVISIBLE (-7925 2900);
FORCEPROP 1 LAST VOLTAGE 0.0V
J 0
(-8045 2857);
DISPLAY 0.340426 (-8045 2857);
PAINT SKYBLUE (-8045 2857);
DISPLAY INVISIBLE (-8045 2857);
FORCEPROP 1 LAST SIZE 1B
J 0
(-7925 2850);
DISPLAY 2.382979 (-7925 2850);
PAINT GREEN (-7925 2850);
DISPLAY INVISIBLE (-7925 2850);
FORCEPROP 1 LAST BODY_TYPE PLUMBING
J 0
(-8045 2857);
DISPLAY 0.340426 (-8045 2857);
PAINT GREEN (-8045 2857);
DISPLAY INVISIBLE (-8045 2857);
FORCEPROP 1 LAST HDL_POWER GND
J 0
(-8000 3050);
PAINT GREEN (-8000 3050);
DISPLAY INVISIBLE (-8000 3050);
FORCEPROP 2 LAST CDS_LIB mstr_symbols
J 0
(-8000 2900);
DISPLAY INVISIBLE (-8000 2900);
FORCEADD TPAD-SE-2P-GP..1
R 2
(-8300 2625);
FORCEPROP 1 LAST VALUE TPAD-SE-2P-GP
J 2
(-8225 2490);
DISPLAY 0.617021 (-8225 2490);
PAINT GREEN (-8225 2490);
FORCEPROP 1 LAST LOCATION T1P27
J 2
(-8325 2740);
DISPLAY 0.617021 (-8325 2740);
PAINT GREEN (-8325 2740);
FORCEPROP 1 LAST PATH I54
J 2
(-8300 2665);
DISPLAY 0.617021 (-8300 2665);
PAINT GREEN (-8300 2665);
DISPLAY INVISIBLE (-8300 2665);
FORCEPROP 1 LAST PACK_TYPE DISCRET-GA1
J 2
(-8300 2625);
DISPLAY 0.617021 (-8300 2625);
PAINT GREEN (-8300 2625);
DISPLAY INVISIBLE (-8300 2625);
FORCEPROP 1 LAST PART_NUMBER ZZ.00PAD.NU1
J 2
(-8300 2586);
DISPLAY 0.617021 (-8300 2586);
PAINT GREEN (-8300 2586);
DISPLAY INVISIBLE (-8300 2586);
FORCEPROP 1 LAST CDS_LMAN_SYM_OUTLINE -75,100,75,-100
J 2
(-8300 2625);
DISPLAY 0.468085 (-8300 2625);
PAINT GREEN (-8300 2625);
DISPLAY INVISIBLE (-8300 2625);
FORCEPROP 2 LAST CDS_LIB w_hdl
J 0
(-8300 2625);
DISPLAY INVISIBLE (-8300 2625);
FORCEADD GND..1
(-8000 2425);
FORCEPROP 3 LASTPIN (-8000 2475) SIG_NAME GND\g
J 0
(-7990 2485);
DISPLAY 0.659574 (-7990 2485);
PAINT MONO (-7990 2485);
DISPLAY INVISIBLE (-7990 2485);
FORCEPROP 1 LAST PATH I55
J 0
(-7925 2425);
DISPLAY 0.872340 (-7925 2425);
PAINT AQUA (-7925 2425);
DISPLAY INVISIBLE (-7925 2425);
FORCEPROP 1 LAST VOLTAGE 0.0V
J 0
(-8045 2382);
DISPLAY 0.340426 (-8045 2382);
PAINT SKYBLUE (-8045 2382);
DISPLAY INVISIBLE (-8045 2382);
FORCEPROP 1 LAST SIZE 1B
J 0
(-7925 2375);
DISPLAY 2.382979 (-7925 2375);
PAINT GREEN (-7925 2375);
DISPLAY INVISIBLE (-7925 2375);
FORCEPROP 1 LAST BODY_TYPE PLUMBING
J 0
(-8045 2382);
DISPLAY 0.340426 (-8045 2382);
PAINT GREEN (-8045 2382);
DISPLAY INVISIBLE (-8045 2382);
FORCEPROP 1 LAST HDL_POWER GND
J 0
(-8000 2575);
PAINT GREEN (-8000 2575);
DISPLAY INVISIBLE (-8000 2575);
FORCEPROP 2 LAST CDS_LIB mstr_symbols
J 0
(-8000 2425);
DISPLAY INVISIBLE (-8000 2425);
FORCEADD TPAD-SE-2P-GP..1
R 2
(-6525 3075);
FORCEPROP 1 LAST VALUE TPAD-SE-2P-GP
J 2
(-6450 2940);
DISPLAY 0.617021 (-6450 2940);
PAINT GREEN (-6450 2940);
FORCEPROP 1 LAST LOCATION T1P29
J 2
(-6550 3190);
DISPLAY 0.617021 (-6550 3190);
PAINT GREEN (-6550 3190);
FORCEPROP 1 LAST PATH I56
J 2
(-6525 3115);
DISPLAY 0.617021 (-6525 3115);
PAINT GREEN (-6525 3115);
DISPLAY INVISIBLE (-6525 3115);
FORCEPROP 1 LAST PACK_TYPE DISCRET-GA1
J 2
(-6525 3075);
DISPLAY 0.617021 (-6525 3075);
PAINT GREEN (-6525 3075);
DISPLAY INVISIBLE (-6525 3075);
FORCEPROP 1 LAST PART_NUMBER ZZ.00PAD.NU1
J 2
(-6525 3036);
DISPLAY 0.617021 (-6525 3036);
PAINT GREEN (-6525 3036);
DISPLAY INVISIBLE (-6525 3036);
FORCEPROP 1 LAST CDS_LMAN_SYM_OUTLINE -75,100,75,-100
J 2
(-6525 3075);
DISPLAY 0.468085 (-6525 3075);
PAINT GREEN (-6525 3075);
DISPLAY INVISIBLE (-6525 3075);
FORCEPROP 2 LAST CDS_LIB w_hdl
J 0
(-6525 3075);
DISPLAY INVISIBLE (-6525 3075);
FORCEADD GND..1
(-6225 3275);
FORCEPROP 3 LASTPIN (-6225 3325) SIG_NAME GND\g
J 0
(-6215 3335);
DISPLAY 0.659574 (-6215 3335);
PAINT MONO (-6215 3335);
DISPLAY INVISIBLE (-6215 3335);
FORCEPROP 1 LAST PATH I57
J 0
(-6150 3275);
DISPLAY 0.872340 (-6150 3275);
PAINT AQUA (-6150 3275);
DISPLAY INVISIBLE (-6150 3275);
FORCEPROP 1 LAST VOLTAGE 0.0V
J 0
(-6270 3232);
DISPLAY 0.340426 (-6270 3232);
PAINT SKYBLUE (-6270 3232);
DISPLAY INVISIBLE (-6270 3232);
FORCEPROP 1 LAST SIZE 1B
J 0
(-6150 3225);
DISPLAY 2.382979 (-6150 3225);
PAINT GREEN (-6150 3225);
DISPLAY INVISIBLE (-6150 3225);
FORCEPROP 1 LAST BODY_TYPE PLUMBING
J 0
(-6270 3232);
DISPLAY 0.340426 (-6270 3232);
PAINT GREEN (-6270 3232);
DISPLAY INVISIBLE (-6270 3232);
FORCEPROP 1 LAST HDL_POWER GND
J 0
(-6225 3425);
PAINT GREEN (-6225 3425);
DISPLAY INVISIBLE (-6225 3425);
FORCEPROP 2 LAST CDS_LIB mstr_symbols
J 0
(-6225 3275);
DISPLAY INVISIBLE (-6225 3275);
FORCEADD GND..1
(-6225 2875);
FORCEPROP 3 LASTPIN (-6225 2925) SIG_NAME GND\g
J 0
(-6215 2935);
DISPLAY 0.659574 (-6215 2935);
PAINT MONO (-6215 2935);
DISPLAY INVISIBLE (-6215 2935);
FORCEPROP 1 LAST PATH I58
J 0
(-6150 2875);
DISPLAY 0.872340 (-6150 2875);
PAINT AQUA (-6150 2875);
DISPLAY INVISIBLE (-6150 2875);
FORCEPROP 1 LAST VOLTAGE 0.0V
J 0
(-6270 2832);
DISPLAY 0.340426 (-6270 2832);
PAINT SKYBLUE (-6270 2832);
DISPLAY INVISIBLE (-6270 2832);
FORCEPROP 1 LAST SIZE 1B
J 0
(-6150 2825);
DISPLAY 2.382979 (-6150 2825);
PAINT GREEN (-6150 2825);
DISPLAY INVISIBLE (-6150 2825);
FORCEPROP 1 LAST BODY_TYPE PLUMBING
J 0
(-6270 2832);
DISPLAY 0.340426 (-6270 2832);
PAINT GREEN (-6270 2832);
DISPLAY INVISIBLE (-6270 2832);
FORCEPROP 1 LAST HDL_POWER GND
J 0
(-6225 3025);
PAINT GREEN (-6225 3025);
DISPLAY INVISIBLE (-6225 3025);
FORCEPROP 2 LAST CDS_LIB mstr_symbols
J 0
(-6225 2875);
DISPLAY INVISIBLE (-6225 2875);
FORCEADD GND..1
(-6225 2400);
FORCEPROP 3 LASTPIN (-6225 2450) SIG_NAME GND\g
J 0
(-6215 2460);
DISPLAY 0.659574 (-6215 2460);
PAINT MONO (-6215 2460);
DISPLAY INVISIBLE (-6215 2460);
FORCEPROP 1 LAST PATH I59
J 0
(-6150 2400);
DISPLAY 0.872340 (-6150 2400);
PAINT AQUA (-6150 2400);
DISPLAY INVISIBLE (-6150 2400);
FORCEPROP 1 LAST VOLTAGE 0.0V
J 0
(-6270 2357);
DISPLAY 0.340426 (-6270 2357);
PAINT SKYBLUE (-6270 2357);
DISPLAY INVISIBLE (-6270 2357);
FORCEPROP 1 LAST SIZE 1B
J 0
(-6150 2350);
DISPLAY 2.382979 (-6150 2350);
PAINT GREEN (-6150 2350);
DISPLAY INVISIBLE (-6150 2350);
FORCEPROP 1 LAST BODY_TYPE PLUMBING
J 0
(-6270 2357);
DISPLAY 0.340426 (-6270 2357);
PAINT GREEN (-6270 2357);
DISPLAY INVISIBLE (-6270 2357);
FORCEPROP 1 LAST HDL_POWER GND
J 0
(-6225 2550);
PAINT GREEN (-6225 2550);
DISPLAY INVISIBLE (-6225 2550);
FORCEPROP 2 LAST CDS_LIB mstr_symbols
J 0
(-6225 2400);
DISPLAY INVISIBLE (-6225 2400);
FORCEADD GND..1
(-8425 5550);
FORCEPROP 3 LASTPIN (-8425 5600) SIG_NAME GND\g
J 0
(-8415 5610);
DISPLAY 0.659574 (-8415 5610);
PAINT MONO (-8415 5610);
DISPLAY INVISIBLE (-8415 5610);
FORCEPROP 1 LAST PATH I6
J 0
(-8350 5550);
DISPLAY 0.872340 (-8350 5550);
PAINT AQUA (-8350 5550);
DISPLAY INVISIBLE (-8350 5550);
FORCEPROP 1 LAST VOLTAGE 0.0V
J 0
(-8470 5507);
DISPLAY 0.340426 (-8470 5507);
PAINT SKYBLUE (-8470 5507);
DISPLAY INVISIBLE (-8470 5507);
FORCEPROP 1 LAST SIZE 1B
J 0
(-8350 5500);
DISPLAY 2.382979 (-8350 5500);
PAINT GREEN (-8350 5500);
DISPLAY INVISIBLE (-8350 5500);
FORCEPROP 1 LAST BODY_TYPE PLUMBING
J 0
(-8470 5507);
DISPLAY 0.340426 (-8470 5507);
PAINT GREEN (-8470 5507);
DISPLAY INVISIBLE (-8470 5507);
FORCEPROP 1 LAST HDL_POWER GND
J 0
(-8425 5700);
PAINT GREEN (-8425 5700);
DISPLAY INVISIBLE (-8425 5700);
FORCEPROP 2 LAST CDS_LIB mstr_symbols
J 0
(-8425 5550);
DISPLAY INVISIBLE (-8425 5550);
FORCEADD TPAD-SE-2P-GP..1
R 2
(-6525 3475);
FORCEPROP 1 LAST VALUE TPAD-SE-2P-GP
J 2
(-6450 3340);
DISPLAY 0.617021 (-6450 3340);
PAINT GREEN (-6450 3340);
FORCEPROP 1 LAST LOCATION T1P28
J 2
(-6550 3590);
DISPLAY 0.617021 (-6550 3590);
PAINT GREEN (-6550 3590);
FORCEPROP 1 LAST PATH I60
J 2
(-6525 3515);
DISPLAY 0.617021 (-6525 3515);
PAINT GREEN (-6525 3515);
DISPLAY INVISIBLE (-6525 3515);
FORCEPROP 1 LAST PACK_TYPE DISCRET-GA1
J 2
(-6525 3475);
DISPLAY 0.617021 (-6525 3475);
PAINT GREEN (-6525 3475);
DISPLAY INVISIBLE (-6525 3475);
FORCEPROP 1 LAST PART_NUMBER ZZ.00PAD.NU1
J 2
(-6525 3436);
DISPLAY 0.617021 (-6525 3436);
PAINT GREEN (-6525 3436);
DISPLAY INVISIBLE (-6525 3436);
FORCEPROP 2 LAST CDS_LIB w_hdl
J 2
(-6525 3475);
DISPLAY INVISIBLE (-6525 3475);
FORCEPROP 1 LAST CDS_LMAN_SYM_OUTLINE -75,100,75,-100
J 2
(-6525 3475);
DISPLAY 0.468085 (-6525 3475);
PAINT GREEN (-6525 3475);
DISPLAY INVISIBLE (-6525 3475);
FORCEADD TPAD-SE-2P-GP..1
R 2
(-6525 2600);
FORCEPROP 1 LAST VALUE TPAD-SE-2P-GP
J 2
(-6450 2465);
DISPLAY 0.617021 (-6450 2465);
PAINT GREEN (-6450 2465);
FORCEPROP 1 LAST LOCATION T1P30
J 2
(-6550 2715);
DISPLAY 0.617021 (-6550 2715);
PAINT GREEN (-6550 2715);
FORCEPROP 1 LAST PATH I61
J 2
(-6525 2640);
DISPLAY 0.617021 (-6525 2640);
PAINT GREEN (-6525 2640);
DISPLAY INVISIBLE (-6525 2640);
FORCEPROP 1 LAST PACK_TYPE DISCRET-GA1
J 2
(-6525 2600);
DISPLAY 0.617021 (-6525 2600);
PAINT GREEN (-6525 2600);
DISPLAY INVISIBLE (-6525 2600);
FORCEPROP 1 LAST PART_NUMBER ZZ.00PAD.NU1
J 2
(-6525 2561);
DISPLAY 0.617021 (-6525 2561);
PAINT GREEN (-6525 2561);
DISPLAY INVISIBLE (-6525 2561);
FORCEPROP 1 LAST CDS_LMAN_SYM_OUTLINE -75,100,75,-100
J 2
(-6525 2600);
DISPLAY 0.468085 (-6525 2600);
PAINT GREEN (-6525 2600);
DISPLAY INVISIBLE (-6525 2600);
FORCEPROP 2 LAST CDS_LIB w_hdl
J 0
(-6525 2600);
DISPLAY INVISIBLE (-6525 2600);
FORCEADD TPAD-SE-2P-GP..1
R 2
(-2750 3450);
FORCEPROP 1 LAST VALUE TPAD-SE-2P-GP
J 2
(-2675 3315);
DISPLAY 0.617021 (-2675 3315);
PAINT GREEN (-2675 3315);
FORCEPROP 1 LAST LOCATION T1P34
J 2
(-2775 3565);
DISPLAY 0.617021 (-2775 3565);
PAINT GREEN (-2775 3565);
FORCEPROP 1 LAST CDS_LMAN_SYM_OUTLINE -75,100,75,-100
J 2
(-2750 3450);
DISPLAY 0.468085 (-2750 3450);
PAINT GREEN (-2750 3450);
DISPLAY INVISIBLE (-2750 3450);
FORCEPROP 2 LAST CDS_LIB w_hdl
J 2
(-2750 3450);
DISPLAY INVISIBLE (-2750 3450);
FORCEPROP 1 LAST PART_NUMBER ZZ.00PAD.NU1
J 2
(-2750 3411);
DISPLAY 0.617021 (-2750 3411);
PAINT GREEN (-2750 3411);
DISPLAY INVISIBLE (-2750 3411);
FORCEPROP 1 LAST PACK_TYPE DISCRET-GA1
J 2
(-2750 3450);
DISPLAY 0.617021 (-2750 3450);
PAINT GREEN (-2750 3450);
DISPLAY INVISIBLE (-2750 3450);
FORCEPROP 1 LAST PATH I62
J 2
(-2750 3490);
DISPLAY 0.617021 (-2750 3490);
PAINT GREEN (-2750 3490);
DISPLAY INVISIBLE (-2750 3490);
FORCEADD TPAD-SE-2P-GP..1
R 2
(-2750 2575);
FORCEPROP 1 LAST VALUE TPAD-SE-2P-GP
J 2
(-2675 2440);
DISPLAY 0.617021 (-2675 2440);
PAINT GREEN (-2675 2440);
FORCEPROP 1 LAST LOCATION T1P36
J 2
(-2775 2690);
DISPLAY 0.617021 (-2775 2690);
PAINT GREEN (-2775 2690);
FORCEPROP 2 LAST CDS_LIB w_hdl
J 0
(-2750 2575);
DISPLAY INVISIBLE (-2750 2575);
FORCEPROP 1 LAST CDS_LMAN_SYM_OUTLINE -75,100,75,-100
J 2
(-2750 2575);
DISPLAY 0.468085 (-2750 2575);
PAINT GREEN (-2750 2575);
DISPLAY INVISIBLE (-2750 2575);
FORCEPROP 1 LAST PART_NUMBER ZZ.00PAD.NU1
J 2
(-2750 2536);
DISPLAY 0.617021 (-2750 2536);
PAINT GREEN (-2750 2536);
DISPLAY INVISIBLE (-2750 2536);
FORCEPROP 1 LAST PACK_TYPE DISCRET-GA1
J 2
(-2750 2575);
DISPLAY 0.617021 (-2750 2575);
PAINT GREEN (-2750 2575);
DISPLAY INVISIBLE (-2750 2575);
FORCEPROP 1 LAST PATH I63
J 2
(-2750 2615);
DISPLAY 0.617021 (-2750 2615);
PAINT GREEN (-2750 2615);
DISPLAY INVISIBLE (-2750 2615);
FORCEADD GND..1
(-2450 2375);
FORCEPROP 3 LASTPIN (-2450 2425) SIG_NAME GND\g
J 0
(-2440 2435);
DISPLAY 0.659574 (-2440 2435);
PAINT MONO (-2440 2435);
DISPLAY INVISIBLE (-2440 2435);
FORCEPROP 2 LAST CDS_LIB mstr_symbols
J 0
(-2450 2375);
DISPLAY INVISIBLE (-2450 2375);
FORCEPROP 1 LAST HDL_POWER GND
J 0
(-2450 2525);
PAINT GREEN (-2450 2525);
DISPLAY INVISIBLE (-2450 2525);
FORCEPROP 1 LAST BODY_TYPE PLUMBING
J 0
(-2495 2332);
DISPLAY 0.340426 (-2495 2332);
PAINT GREEN (-2495 2332);
DISPLAY INVISIBLE (-2495 2332);
FORCEPROP 1 LAST SIZE 1B
J 0
(-2375 2325);
DISPLAY 2.382979 (-2375 2325);
PAINT GREEN (-2375 2325);
DISPLAY INVISIBLE (-2375 2325);
FORCEPROP 1 LAST VOLTAGE 0.0V
J 0
(-2495 2332);
DISPLAY 0.340426 (-2495 2332);
PAINT SKYBLUE (-2495 2332);
DISPLAY INVISIBLE (-2495 2332);
FORCEPROP 1 LAST PATH I64
J 0
(-2375 2375);
DISPLAY 0.872340 (-2375 2375);
PAINT AQUA (-2375 2375);
DISPLAY INVISIBLE (-2375 2375);
FORCEADD GND..1
(-2450 3250);
FORCEPROP 3 LASTPIN (-2450 3300) SIG_NAME GND\g
J 0
(-2440 3310);
DISPLAY 0.659574 (-2440 3310);
PAINT MONO (-2440 3310);
DISPLAY INVISIBLE (-2440 3310);
FORCEPROP 2 LAST CDS_LIB mstr_symbols
J 0
(-2450 3250);
DISPLAY INVISIBLE (-2450 3250);
FORCEPROP 1 LAST HDL_POWER GND
J 0
(-2450 3400);
PAINT GREEN (-2450 3400);
DISPLAY INVISIBLE (-2450 3400);
FORCEPROP 1 LAST BODY_TYPE PLUMBING
J 0
(-2495 3207);
DISPLAY 0.340426 (-2495 3207);
PAINT GREEN (-2495 3207);
DISPLAY INVISIBLE (-2495 3207);
FORCEPROP 1 LAST SIZE 1B
J 0
(-2375 3200);
DISPLAY 2.382979 (-2375 3200);
PAINT GREEN (-2375 3200);
DISPLAY INVISIBLE (-2375 3200);
FORCEPROP 1 LAST VOLTAGE 0.0V
J 0
(-2495 3207);
DISPLAY 0.340426 (-2495 3207);
PAINT SKYBLUE (-2495 3207);
DISPLAY INVISIBLE (-2495 3207);
FORCEPROP 1 LAST PATH I65
J 0
(-2375 3250);
DISPLAY 0.872340 (-2375 3250);
PAINT AQUA (-2375 3250);
DISPLAY INVISIBLE (-2375 3250);
FORCEADD GND..1
(-2450 2850);
FORCEPROP 3 LASTPIN (-2450 2900) SIG_NAME GND\g
J 0
(-2440 2910);
DISPLAY 0.659574 (-2440 2910);
PAINT MONO (-2440 2910);
DISPLAY INVISIBLE (-2440 2910);
FORCEPROP 2 LAST CDS_LIB mstr_symbols
J 0
(-2450 2850);
DISPLAY INVISIBLE (-2450 2850);
FORCEPROP 1 LAST HDL_POWER GND
J 0
(-2450 3000);
PAINT GREEN (-2450 3000);
DISPLAY INVISIBLE (-2450 3000);
FORCEPROP 1 LAST BODY_TYPE PLUMBING
J 0
(-2495 2807);
DISPLAY 0.340426 (-2495 2807);
PAINT GREEN (-2495 2807);
DISPLAY INVISIBLE (-2495 2807);
FORCEPROP 1 LAST SIZE 1B
J 0
(-2375 2800);
DISPLAY 2.382979 (-2375 2800);
PAINT GREEN (-2375 2800);
DISPLAY INVISIBLE (-2375 2800);
FORCEPROP 1 LAST VOLTAGE 0.0V
J 0
(-2495 2807);
DISPLAY 0.340426 (-2495 2807);
PAINT SKYBLUE (-2495 2807);
DISPLAY INVISIBLE (-2495 2807);
FORCEPROP 1 LAST PATH I66
J 0
(-2375 2850);
DISPLAY 0.872340 (-2375 2850);
PAINT AQUA (-2375 2850);
DISPLAY INVISIBLE (-2375 2850);
FORCEADD TPAD-SE-2P-GP..1
R 2
(-2750 3050);
FORCEPROP 1 LAST VALUE TPAD-SE-2P-GP
J 2
(-2675 2915);
DISPLAY 0.617021 (-2675 2915);
PAINT GREEN (-2675 2915);
FORCEPROP 1 LAST LOCATION T1P35
J 2
(-2775 3165);
DISPLAY 0.617021 (-2775 3165);
PAINT GREEN (-2775 3165);
FORCEPROP 2 LAST CDS_LIB w_hdl
J 0
(-2750 3050);
DISPLAY INVISIBLE (-2750 3050);
FORCEPROP 1 LAST CDS_LMAN_SYM_OUTLINE -75,100,75,-100
J 2
(-2750 3050);
DISPLAY 0.468085 (-2750 3050);
PAINT GREEN (-2750 3050);
DISPLAY INVISIBLE (-2750 3050);
FORCEPROP 1 LAST PART_NUMBER ZZ.00PAD.NU1
J 2
(-2750 3011);
DISPLAY 0.617021 (-2750 3011);
PAINT GREEN (-2750 3011);
DISPLAY INVISIBLE (-2750 3011);
FORCEPROP 1 LAST PACK_TYPE DISCRET-GA1
J 2
(-2750 3050);
DISPLAY 0.617021 (-2750 3050);
PAINT GREEN (-2750 3050);
DISPLAY INVISIBLE (-2750 3050);
FORCEPROP 1 LAST PATH I67
J 2
(-2750 3090);
DISPLAY 0.617021 (-2750 3090);
PAINT GREEN (-2750 3090);
DISPLAY INVISIBLE (-2750 3090);
FORCEADD GND..1
(-4225 3275);
FORCEPROP 3 LASTPIN (-4225 3325) SIG_NAME GND\g
J 0
(-4215 3335);
DISPLAY 0.659574 (-4215 3335);
PAINT MONO (-4215 3335);
DISPLAY INVISIBLE (-4215 3335);
FORCEPROP 2 LAST CDS_LIB mstr_symbols
J 0
(-4225 3275);
DISPLAY INVISIBLE (-4225 3275);
FORCEPROP 1 LAST HDL_POWER GND
J 0
(-4225 3425);
PAINT GREEN (-4225 3425);
DISPLAY INVISIBLE (-4225 3425);
FORCEPROP 1 LAST BODY_TYPE PLUMBING
J 0
(-4270 3232);
DISPLAY 0.340426 (-4270 3232);
PAINT GREEN (-4270 3232);
DISPLAY INVISIBLE (-4270 3232);
FORCEPROP 1 LAST SIZE 1B
J 0
(-4150 3225);
DISPLAY 2.382979 (-4150 3225);
PAINT GREEN (-4150 3225);
DISPLAY INVISIBLE (-4150 3225);
FORCEPROP 1 LAST VOLTAGE 0.0V
J 0
(-4270 3232);
DISPLAY 0.340426 (-4270 3232);
PAINT SKYBLUE (-4270 3232);
DISPLAY INVISIBLE (-4270 3232);
FORCEPROP 1 LAST PATH I68
J 0
(-4150 3275);
DISPLAY 0.872340 (-4150 3275);
PAINT AQUA (-4150 3275);
DISPLAY INVISIBLE (-4150 3275);
FORCEADD GND..1
(-4225 2875);
FORCEPROP 3 LASTPIN (-4225 2925) SIG_NAME GND\g
J 0
(-4215 2935);
DISPLAY 0.659574 (-4215 2935);
PAINT MONO (-4215 2935);
DISPLAY INVISIBLE (-4215 2935);
FORCEPROP 2 LAST CDS_LIB mstr_symbols
J 0
(-4225 2875);
DISPLAY INVISIBLE (-4225 2875);
FORCEPROP 1 LAST HDL_POWER GND
J 0
(-4225 3025);
PAINT GREEN (-4225 3025);
DISPLAY INVISIBLE (-4225 3025);
FORCEPROP 1 LAST BODY_TYPE PLUMBING
J 0
(-4270 2832);
DISPLAY 0.340426 (-4270 2832);
PAINT GREEN (-4270 2832);
DISPLAY INVISIBLE (-4270 2832);
FORCEPROP 1 LAST SIZE 1B
J 0
(-4150 2825);
DISPLAY 2.382979 (-4150 2825);
PAINT GREEN (-4150 2825);
DISPLAY INVISIBLE (-4150 2825);
FORCEPROP 1 LAST VOLTAGE 0.0V
J 0
(-4270 2832);
DISPLAY 0.340426 (-4270 2832);
PAINT SKYBLUE (-4270 2832);
DISPLAY INVISIBLE (-4270 2832);
FORCEPROP 1 LAST PATH I69
J 0
(-4150 2875);
DISPLAY 0.872340 (-4150 2875);
PAINT AQUA (-4150 2875);
DISPLAY INVISIBLE (-4150 2875);
FORCEADD TPAD-DIFF-4P-GP..1
(-7975 4925);
FORCEPROP 1 LAST LOCATION T1P4
J 0
(-7950 5040);
DISPLAY 0.617021 (-7950 5040);
PAINT GREEN (-7950 5040);
FORCEPROP 2 LASTPIN (-8200 4875) $PN GND2
J 2
(-8210 4885);
DISPLAY 0.808511 (-8210 4885);
PAINT ORANGE (-8210 4885);
FORCEPROP 2 LASTPIN (-8200 4975) $PN GND1
J 2
(-8210 4985);
DISPLAY 0.808511 (-8210 4985);
PAINT ORANGE (-8210 4985);
FORCEPROP 1 LAST VALUE TPAD-DIFF-4P-GP
J 0
(-8050 4795);
DISPLAY 0.617021 (-8050 4795);
PAINT GREEN (-8050 4795);
FORCEPROP 2 LASTPIN (-7750 4875) $PN 2
J 0
(-7740 4885);
DISPLAY 0.808511 (-7740 4885);
PAINT ORANGE (-7740 4885);
FORCEPROP 2 LASTPIN (-7750 4975) $PN 1
J 0
(-7740 4985);
DISPLAY 0.808511 (-7740 4985);
PAINT ORANGE (-7740 4985);
FORCEPROP 1 LAST PATH I7
J 0
(-7975 5032);
DISPLAY 0.617021 (-7975 5032);
PAINT GREEN (-7975 5032);
DISPLAY INVISIBLE (-7975 5032);
FORCEPROP 1 LAST PART_NUMBER ZZ.00PAD.NW1
J 0
(-7975 4821);
DISPLAY 0.617021 (-7975 4821);
PAINT GREEN (-7975 4821);
DISPLAY INVISIBLE (-7975 4821);
FORCEPROP 1 LAST CDS_LMAN_SYM_OUTLINE -75,100,75,-100
J 0
(-7975 4925);
DISPLAY 0.468085 (-7975 4925);
PAINT GREEN (-7975 4925);
DISPLAY INVISIBLE (-7975 4925);
FORCEPROP 2 LAST CDS_LIB w_hdl
J 0
(-7975 4925);
DISPLAY INVISIBLE (-7975 4925);
FORCEPROP 1 LAST PACK_TYPE DISCRET-GB3
J 0
(-7975 4925);
DISPLAY 0.617021 (-7975 4925);
PAINT GREEN (-7975 4925);
DISPLAY INVISIBLE (-7975 4925);
FORCEPROP 2 LAST SEC 1
J 0
(-7950 5075);
DISPLAY 0.680851 (-7950 5075);
PAINT MONO (-7950 5075);
DISPLAY INVISIBLE (-7950 5075);
FORCEPROP 2 LAST SEC_TYPE DISCRET-GB3
J 0
(-7950 5075);
DISPLAY 1.021277 (-7950 5075);
PAINT ORANGE (-7950 5075);
DISPLAY INVISIBLE (-7950 5075);
FORCEADD GND..1
(-4225 2400);
FORCEPROP 3 LASTPIN (-4225 2450) SIG_NAME GND\g
J 0
(-4215 2460);
DISPLAY 0.659574 (-4215 2460);
PAINT MONO (-4215 2460);
DISPLAY INVISIBLE (-4215 2460);
FORCEPROP 2 LAST CDS_LIB mstr_symbols
J 0
(-4225 2400);
DISPLAY INVISIBLE (-4225 2400);
FORCEPROP 1 LAST HDL_POWER GND
J 0
(-4225 2550);
PAINT GREEN (-4225 2550);
DISPLAY INVISIBLE (-4225 2550);
FORCEPROP 1 LAST BODY_TYPE PLUMBING
J 0
(-4270 2357);
DISPLAY 0.340426 (-4270 2357);
PAINT GREEN (-4270 2357);
DISPLAY INVISIBLE (-4270 2357);
FORCEPROP 1 LAST SIZE 1B
J 0
(-4150 2350);
DISPLAY 2.382979 (-4150 2350);
PAINT GREEN (-4150 2350);
DISPLAY INVISIBLE (-4150 2350);
FORCEPROP 1 LAST VOLTAGE 0.0V
J 0
(-4270 2357);
DISPLAY 0.340426 (-4270 2357);
PAINT SKYBLUE (-4270 2357);
DISPLAY INVISIBLE (-4270 2357);
FORCEPROP 1 LAST PATH I70
J 0
(-4150 2400);
DISPLAY 0.872340 (-4150 2400);
PAINT AQUA (-4150 2400);
DISPLAY INVISIBLE (-4150 2400);
FORCEADD TPAD-SE-2P-GP..1
R 2
(-4525 3475);
FORCEPROP 1 LAST VALUE TPAD-SE-2P-GP
J 2
(-4450 3340);
DISPLAY 0.617021 (-4450 3340);
PAINT GREEN (-4450 3340);
FORCEPROP 1 LAST LOCATION T1P31
J 2
(-4550 3590);
DISPLAY 0.617021 (-4550 3590);
PAINT GREEN (-4550 3590);
FORCEPROP 1 LAST CDS_LMAN_SYM_OUTLINE -75,100,75,-100
J 2
(-4525 3475);
DISPLAY 0.468085 (-4525 3475);
PAINT GREEN (-4525 3475);
DISPLAY INVISIBLE (-4525 3475);
FORCEPROP 2 LAST CDS_LIB w_hdl
J 2
(-4525 3475);
DISPLAY INVISIBLE (-4525 3475);
FORCEPROP 1 LAST PART_NUMBER ZZ.00PAD.NU1
J 2
(-4525 3436);
DISPLAY 0.617021 (-4525 3436);
PAINT GREEN (-4525 3436);
DISPLAY INVISIBLE (-4525 3436);
FORCEPROP 1 LAST PACK_TYPE DISCRET-GA1
J 2
(-4525 3475);
DISPLAY 0.617021 (-4525 3475);
PAINT GREEN (-4525 3475);
DISPLAY INVISIBLE (-4525 3475);
FORCEPROP 1 LAST PATH I71
J 2
(-4525 3515);
DISPLAY 0.617021 (-4525 3515);
PAINT GREEN (-4525 3515);
DISPLAY INVISIBLE (-4525 3515);
FORCEADD TPAD-SE-2P-GP..1
R 2
(-4525 3075);
FORCEPROP 1 LAST VALUE TPAD-SE-2P-GP
J 2
(-4450 2940);
DISPLAY 0.617021 (-4450 2940);
PAINT GREEN (-4450 2940);
FORCEPROP 1 LAST LOCATION T1P32
J 2
(-4550 3190);
DISPLAY 0.617021 (-4550 3190);
PAINT GREEN (-4550 3190);
FORCEPROP 2 LAST CDS_LIB w_hdl
J 0
(-4525 3075);
DISPLAY INVISIBLE (-4525 3075);
FORCEPROP 1 LAST CDS_LMAN_SYM_OUTLINE -75,100,75,-100
J 2
(-4525 3075);
DISPLAY 0.468085 (-4525 3075);
PAINT GREEN (-4525 3075);
DISPLAY INVISIBLE (-4525 3075);
FORCEPROP 1 LAST PART_NUMBER ZZ.00PAD.NU1
J 2
(-4525 3036);
DISPLAY 0.617021 (-4525 3036);
PAINT GREEN (-4525 3036);
DISPLAY INVISIBLE (-4525 3036);
FORCEPROP 1 LAST PACK_TYPE DISCRET-GA1
J 2
(-4525 3075);
DISPLAY 0.617021 (-4525 3075);
PAINT GREEN (-4525 3075);
DISPLAY INVISIBLE (-4525 3075);
FORCEPROP 1 LAST PATH I72
J 2
(-4525 3115);
DISPLAY 0.617021 (-4525 3115);
PAINT GREEN (-4525 3115);
DISPLAY INVISIBLE (-4525 3115);
FORCEADD TPAD-SE-2P-GP..1
R 2
(-4525 2600);
FORCEPROP 1 LAST VALUE TPAD-SE-2P-GP
J 2
(-4450 2465);
DISPLAY 0.617021 (-4450 2465);
PAINT GREEN (-4450 2465);
FORCEPROP 1 LAST LOCATION T1P33
J 2
(-4550 2715);
DISPLAY 0.617021 (-4550 2715);
PAINT GREEN (-4550 2715);
FORCEPROP 2 LAST CDS_LIB w_hdl
J 0
(-4525 2600);
DISPLAY INVISIBLE (-4525 2600);
FORCEPROP 1 LAST CDS_LMAN_SYM_OUTLINE -75,100,75,-100
J 2
(-4525 2600);
DISPLAY 0.468085 (-4525 2600);
PAINT GREEN (-4525 2600);
DISPLAY INVISIBLE (-4525 2600);
FORCEPROP 1 LAST PART_NUMBER ZZ.00PAD.NU1
J 2
(-4525 2561);
DISPLAY 0.617021 (-4525 2561);
PAINT GREEN (-4525 2561);
DISPLAY INVISIBLE (-4525 2561);
FORCEPROP 1 LAST PACK_TYPE DISCRET-GA1
J 2
(-4525 2600);
DISPLAY 0.617021 (-4525 2600);
PAINT GREEN (-4525 2600);
DISPLAY INVISIBLE (-4525 2600);
FORCEPROP 1 LAST PATH I73
J 2
(-4525 2640);
DISPLAY 0.617021 (-4525 2640);
PAINT GREEN (-4525 2640);
DISPLAY INVISIBLE (-4525 2640);
FORCEADD TPAD-DIFF-4P-GP..1
(-7975 5325);
FORCEPROP 2 LASTPIN (-7750 5375) $PN 1
J 0
(-7740 5385);
DISPLAY 0.808511 (-7740 5385);
PAINT ORANGE (-7740 5385);
FORCEPROP 2 LASTPIN (-8200 5275) $PN GND2
J 2
(-8210 5285);
DISPLAY 0.808511 (-8210 5285);
PAINT ORANGE (-8210 5285);
FORCEPROP 2 LASTPIN (-8200 5375) $PN GND1
J 2
(-8210 5385);
DISPLAY 0.808511 (-8210 5385);
PAINT ORANGE (-8210 5385);
FORCEPROP 2 LASTPIN (-7750 5275) $PN 2
J 0
(-7740 5285);
DISPLAY 0.808511 (-7740 5285);
PAINT ORANGE (-7740 5285);
FORCEPROP 1 LAST VALUE TPAD-DIFF-4P-GP
J 0
(-8050 5195);
DISPLAY 0.617021 (-8050 5195);
PAINT GREEN (-8050 5195);
FORCEPROP 1 LAST LOCATION T1P3
J 0
(-7950 5440);
DISPLAY 0.617021 (-7950 5440);
PAINT GREEN (-7950 5440);
FORCEPROP 1 LAST PATH I8
J 0
(-7975 5432);
DISPLAY 0.617021 (-7975 5432);
PAINT GREEN (-7975 5432);
DISPLAY INVISIBLE (-7975 5432);
FORCEPROP 1 LAST PART_NUMBER ZZ.00PAD.NW1
J 0
(-7975 5221);
DISPLAY 0.617021 (-7975 5221);
PAINT GREEN (-7975 5221);
DISPLAY INVISIBLE (-7975 5221);
FORCEPROP 1 LAST CDS_LMAN_SYM_OUTLINE -75,100,75,-100
J 0
(-7975 5325);
DISPLAY 0.468085 (-7975 5325);
PAINT GREEN (-7975 5325);
DISPLAY INVISIBLE (-7975 5325);
FORCEPROP 2 LAST CDS_LIB w_hdl
J 0
(-7975 5325);
DISPLAY INVISIBLE (-7975 5325);
FORCEPROP 1 LAST PACK_TYPE DISCRET-GB3
J 0
(-7975 5325);
DISPLAY 0.617021 (-7975 5325);
PAINT GREEN (-7975 5325);
DISPLAY INVISIBLE (-7975 5325);
FORCEPROP 2 LAST SEC 1
J 0
(-7950 5475);
DISPLAY 0.680851 (-7950 5475);
PAINT MONO (-7950 5475);
DISPLAY INVISIBLE (-7950 5475);
FORCEPROP 2 LAST SEC_TYPE DISCRET-GB3
J 0
(-7950 5475);
DISPLAY 1.021277 (-7950 5475);
PAINT ORANGE (-7950 5475);
DISPLAY INVISIBLE (-7950 5475);
FORCEADD GND..1
(-8425 5175);
FORCEPROP 3 LASTPIN (-8425 5225) SIG_NAME GND\g
J 0
(-8415 5235);
DISPLAY 0.659574 (-8415 5235);
PAINT MONO (-8415 5235);
DISPLAY INVISIBLE (-8415 5235);
FORCEPROP 1 LAST PATH I9
J 0
(-8350 5175);
DISPLAY 0.872340 (-8350 5175);
PAINT AQUA (-8350 5175);
DISPLAY INVISIBLE (-8350 5175);
FORCEPROP 1 LAST VOLTAGE 0.0V
J 0
(-8470 5132);
DISPLAY 0.340426 (-8470 5132);
PAINT SKYBLUE (-8470 5132);
DISPLAY INVISIBLE (-8470 5132);
FORCEPROP 1 LAST SIZE 1B
J 0
(-8350 5125);
DISPLAY 2.382979 (-8350 5125);
PAINT GREEN (-8350 5125);
DISPLAY INVISIBLE (-8350 5125);
FORCEPROP 1 LAST BODY_TYPE PLUMBING
J 0
(-8470 5132);
DISPLAY 0.340426 (-8470 5132);
PAINT GREEN (-8470 5132);
DISPLAY INVISIBLE (-8470 5132);
FORCEPROP 1 LAST HDL_POWER GND
J 0
(-8425 5325);
PAINT GREEN (-8425 5325);
DISPLAY INVISIBLE (-8425 5325);
FORCEPROP 2 LAST CDS_LIB mstr_symbols
J 0
(-8425 5175);
DISPLAY INVISIBLE (-8425 5175);
FORCEADD INTEL_CORP_BPAGE..1
(-950 1525);
FORCEPROP 1 LAST CDS_CON_LAST_MODIFIED Fri Jun 16 17:49:33 2017
J 0
(-2375 1850);
PAINT ORANGE (-2375 1850);
DISPLAY INVISIBLE (-2375 1850);
FORCEPROP 2 LAST CUSTOM_TXT_CDS <XR_PAGE_TITLE>
J 0
(-8840 6775);
DISPLAY 0.638298 (-8840 6775);
PAINT PINK (-8840 6775);
DISPLAY INVISIBLE (-8840 6775);
FORCEPROP 2 LAST CUSTOM_TXT_CDS <CON_LAST_MODIFIED>
J 0
(-4950 1625);
PAINT ORANGE (-4950 1625);
FORCEPROP 2 LAST CUSTOM_TXT_CDS <CURRENT_DESIGN_SHEET> OF <TOTAL_DESIGN_SHEETS>
J 0
(-1450 1550);
PAINT ORANGE (-1450 1550);
FORCEPROP 1 LAST SCH_TITLE COUPON - 1 OF 3
J 0
(-8900 1575);
DISPLAY 2.468085 (-8900 1575);
PAINT ORANGE (-8900 1575);
FORCEPROP 1 LAST COMMENT_BODY TRUE
J 0
(-938 1537);
DISPLAY 0.468085 (-938 1537);
PAINT GREEN (-938 1537);
DISPLAY INVISIBLE (-938 1537);
FORCEPROP 2 LAST CDS_LIB mstr_symbols
J 0
(-950 1525);
PAINT MONO (-950 1525);
DISPLAY INVISIBLE (-950 1525);
FORCEPROP 2 LAST PAGE_BORDER TRUE
J 0
(-8840 6775);
DISPLAY 0.638298 (-8840 6775);
PAINT PINK (-8840 6775);
DISPLAY INVISIBLE (-8840 6775);
FORCEPROP 2 LAST CDS_XR_PAGE_TITLE CR-256 : @BASEBOARD_FAB2_LIB.BASEBOARD_FAB2(SCH_1):PAGE256
J 0
(-8840 6775);
DISPLAY 0.638298 (-8840 6775);
PAINT PINK (-8840 6775);
DISPLAY INVISIBLE (-8840 6775);
WIRE 16 -1 (-8425 4875)(-8425 4825);
WIRE 16 -1 (-8425 4975)(-8425 4875);
WIRE 16 -1 (-8200 4875)(-8425 4875);
WIRE 16 -1 (-8200 4975)(-8425 4975);
WIRE 16 -1 (-8400 4525)(-8400 4475);
WIRE 16 -1 (-8400 4625)(-8400 4525);
WIRE 16 -1 (-8175 4525)(-8400 4525);
WIRE 16 -1 (-8175 4625)(-8400 4625);
WIRE 16 -1 (-8400 4125)(-8400 4075);
WIRE 16 -1 (-8400 4225)(-8400 4125);
WIRE 16 -1 (-8175 4125)(-8400 4125);
WIRE 16 -1 (-8175 4225)(-8400 4225);
WIRE 16 -1 (-6450 6025)(-6450 5975);
WIRE 16 -1 (-6450 6125)(-6450 6025);
WIRE 16 -1 (-6225 6025)(-6450 6025);
WIRE 16 -1 (-6225 6125)(-6450 6125);
WIRE 16 -1 (-6450 5625)(-6450 5575);
WIRE 16 -1 (-6450 5725)(-6450 5625);
WIRE 16 -1 (-6225 5625)(-6450 5625);
WIRE 16 -1 (-6225 5725)(-6450 5725);
WIRE 16 -1 (-6450 5250)(-6450 5200);
WIRE 16 -1 (-6450 5350)(-6450 5250);
WIRE 16 -1 (-6225 5250)(-6450 5250);
WIRE 16 -1 (-6225 5350)(-6450 5350);
WIRE 16 -1 (-6450 4850)(-6450 4800);
WIRE 16 -1 (-6450 4950)(-6450 4850);
WIRE 16 -1 (-6225 4850)(-6450 4850);
WIRE 16 -1 (-6225 4950)(-6450 4950);
WIRE 16 -1 (-6425 4500)(-6425 4450);
WIRE 16 -1 (-6425 4600)(-6425 4500);
WIRE 16 -1 (-6200 4500)(-6425 4500);
WIRE 16 -1 (-6200 4600)(-6425 4600);
WIRE 16 -1 (-6425 4100)(-6425 4050);
WIRE 16 -1 (-6425 4200)(-6425 4100);
WIRE 16 -1 (-6200 4100)(-6425 4100);
WIRE 16 -1 (-6200 4200)(-6425 4200);
WIRE 16 -1 (-4650 5625)(-4650 5575);
WIRE 16 -1 (-4650 5725)(-4650 5625);
WIRE 16 -1 (-4425 5625)(-4650 5625);
WIRE 16 -1 (-4425 5725)(-4650 5725);
WIRE 16 -1 (-4625 4500)(-4625 4450);
WIRE 16 -1 (-4625 4600)(-4625 4500);
WIRE 16 -1 (-4400 4500)(-4625 4500);
WIRE 16 -1 (-4400 4600)(-4625 4600);
WIRE 16 -1 (-8425 6050)(-8425 6000);
WIRE 16 -1 (-8425 6150)(-8425 6050);
WIRE 16 -1 (-8200 6050)(-8425 6050);
WIRE 16 -1 (-8200 6150)(-8425 6150);
WIRE 16 -1 (-2850 6075)(-2850 6025);
WIRE 16 -1 (-2850 6175)(-2850 6075);
WIRE 16 -1 (-2625 6075)(-2850 6075);
WIRE 16 -1 (-2625 6175)(-2850 6175);
WIRE 16 -1 (-2850 4900)(-2850 4850);
WIRE 16 -1 (-2850 5000)(-2850 4900);
WIRE 16 -1 (-2625 4900)(-2850 4900);
WIRE 16 -1 (-2625 5000)(-2850 5000);
WIRE 16 -1 (-2825 4550)(-2825 4500);
WIRE 16 -1 (-2825 4650)(-2825 4550);
WIRE 16 -1 (-2600 4550)(-2825 4550);
WIRE 16 -1 (-2600 4650)(-2825 4650);
WIRE 16 -1 (-2825 4150)(-2825 4100);
WIRE 16 -1 (-2825 4250)(-2825 4150);
WIRE 16 -1 (-2600 4150)(-2825 4150);
WIRE 16 -1 (-2600 4250)(-2825 4250);
WIRE 16 -1 (-8000 3450)(-8000 3350);
WIRE 16 -1 (-8075 3450)(-8000 3450);
WIRE 16 -1 (-8000 3050)(-8000 2950);
WIRE 16 -1 (-8075 3050)(-8000 3050);
WIRE 16 -1 (-8000 2575)(-8000 2475);
WIRE 16 -1 (-8075 2575)(-8000 2575);
WIRE 16 -1 (-6225 3425)(-6225 3325);
WIRE 16 -1 (-6300 3425)(-6225 3425);
WIRE 16 -1 (-6225 3025)(-6225 2925);
WIRE 16 -1 (-6300 3025)(-6225 3025);
WIRE 16 -1 (-6225 2550)(-6225 2450);
WIRE 16 -1 (-6300 2550)(-6225 2550);
WIRE 16 -1 (-8425 5650)(-8425 5600);
WIRE 16 -1 (-8425 5750)(-8425 5650);
WIRE 16 -1 (-8200 5650)(-8425 5650);
WIRE 16 -1 (-8200 5750)(-8425 5750);
WIRE 16 -1 (-2450 2525)(-2450 2425);
WIRE 16 -1 (-2525 2525)(-2450 2525);
WIRE 16 -1 (-2450 3400)(-2450 3300);
WIRE 16 -1 (-2525 3400)(-2450 3400);
WIRE 16 -1 (-2450 3000)(-2450 2900);
WIRE 16 -1 (-2525 3000)(-2450 3000);
WIRE 16 -1 (-4225 3425)(-4225 3325);
WIRE 16 -1 (-4300 3425)(-4225 3425);
WIRE 16 -1 (-4225 3025)(-4225 2925);
WIRE 16 -1 (-4300 3025)(-4225 3025);
WIRE 16 -1 (-4225 2550)(-4225 2450);
WIRE 16 -1 (-4300 2550)(-4225 2550);
WIRE 16 -1 (-8425 5275)(-8425 5225);
WIRE 16 -1 (-8425 5375)(-8425 5275);
WIRE 16 -1 (-8200 5275)(-8425 5275);
WIRE 16 -1 (-8200 5375)(-8425 5375);
WIRE 16 -1 (-7750 5650)(-6775 5650);
FORCEPROP 2 LAST SIG_NAME L3_85OHM_6INCH_DN
J 0
(-7535 5660);
DISPLAY 0.638298 (-7535 5660);
PAINT ORANGE (-7535 5660);
FORCEPROP 2 LASTPROP $XRERR UNIQUE?
J 0
(-6745 5650);
DISPLAY 0.638298 (-6745 5650);
PAINT MONO (-6745 5650);
DISPLAY INVISIBLE (-6745 5650);
WIRE 16 -1 (-8075 2675)(-7100 2675);
FORCEPROP 2 LAST SIG_NAME L5_40OHM_6INCH
J 0
(-7860 2685);
DISPLAY 0.638298 (-7860 2685);
PAINT ORANGE (-7860 2685);
FORCEPROP 2 LASTPROP $XRERR UNIQUE?
J 0
(-7070 2675);
DISPLAY 0.638298 (-7070 2675);
PAINT MONO (-7070 2675);
DISPLAY INVISIBLE (-7070 2675);
WIRE 3 682 (-3200 5800)(-3850 5800);
WIRE 3 682 (-3200 5600)(-3200 5800);
WIRE 3 682 (-3850 5800)(-3850 5600);
WIRE 3 682 (-3850 5600)(-3200 5600);
WIRE 16 -1 (-3975 5625)(-3000 5625);
FORCEPROP 2 LAST SIG_NAME L1_95OHM_6INCH_DN
J 0
(-3760 5635);
DISPLAY 0.638298 (-3760 5635);
PAINT ORANGE (-3760 5635);
FORCEPROP 2 LASTPROP $XRERR UNIQUE?
J 0
(-2970 5625);
DISPLAY 0.638298 (-2970 5625);
PAINT MONO (-2970 5625);
DISPLAY INVISIBLE (-2970 5625);
WIRE 16 -1 (-3975 5725)(-3000 5725);
FORCEPROP 2 LAST SIG_NAME L1_95OHM_6INCH_DP
J 0
(-3760 5735);
DISPLAY 0.638298 (-3760 5735);
PAINT ORANGE (-3760 5735);
FORCEPROP 2 LASTPROP $XRERR UNIQUE?
J 0
(-2970 5725);
DISPLAY 0.638298 (-2970 5725);
PAINT MONO (-2970 5725);
DISPLAY INVISIBLE (-2970 5725);
WIRE 16 -1 (-3950 4600)(-2975 4600);
FORCEPROP 2 LAST SIG_NAME L12_95OHM_6INCH_DP
J 0
(-3735 4610);
DISPLAY 0.638298 (-3735 4610);
PAINT ORANGE (-3735 4610);
FORCEPROP 2 LASTPROP $XRERR UNIQUE?
J 0
(-2945 4600);
DISPLAY 0.638298 (-2945 4600);
PAINT MONO (-2945 4600);
DISPLAY INVISIBLE (-2945 4600);
WIRE 16 -1 (-3950 4500)(-2975 4500);
FORCEPROP 2 LAST SIG_NAME L12_95OHM_6INCH_DN
J 0
(-3735 4510);
DISPLAY 0.638298 (-3735 4510);
PAINT ORANGE (-3735 4510);
FORCEPROP 2 LASTPROP $XRERR UNIQUE?
J 0
(-2945 4500);
DISPLAY 0.638298 (-2945 4500);
PAINT MONO (-2945 4500);
DISPLAY INVISIBLE (-2945 4500);
WIRE 3 682 (-3800 4550)(-3800 4450);
WIRE 3 682 (-3250 4550)(-3800 4550);
WIRE 3 682 (-3800 4450)(-3250 4450);
WIRE 3 682 (-3250 4450)(-3250 4550);
WIRE 16 -1 (-4300 3525)(-3325 3525);
FORCEPROP 2 LAST SIG_NAME L1_50OHM_6INCH
J 0
(-4085 3535);
DISPLAY 0.638298 (-4085 3535);
PAINT ORANGE (-4085 3535);
FORCEPROP 2 LASTPROP $XRERR UNIQUE?
J 0
(-3295 3525);
DISPLAY 0.638298 (-3295 3525);
PAINT MONO (-3295 3525);
DISPLAY INVISIBLE (-3295 3525);
WIRE 16 -1 (-4300 3125)(-3325 3125);
FORCEPROP 2 LAST SIG_NAME L3_50OHM_6INCH
J 0
(-4085 3135);
DISPLAY 0.638298 (-4085 3135);
PAINT ORANGE (-4085 3135);
FORCEPROP 2 LASTPROP $XRERR UNIQUE?
J 0
(-3295 3125);
DISPLAY 0.638298 (-3295 3125);
PAINT MONO (-3295 3125);
DISPLAY INVISIBLE (-3295 3125);
WIRE 16 -1 (-2525 2625)(-1550 2625);
FORCEPROP 2 LAST SIG_NAME L14_50OHM_6INCH
J 0
(-2310 2635);
DISPLAY 0.638298 (-2310 2635);
PAINT ORANGE (-2310 2635);
FORCEPROP 2 LASTPROP $XRERR UNIQUE?
J 0
(-1520 2625);
DISPLAY 0.638298 (-1520 2625);
PAINT MONO (-1520 2625);
DISPLAY INVISIBLE (-1520 2625);
WIRE 16 -1 (-2525 3100)(-1550 3100);
FORCEPROP 2 LAST SIG_NAME L12_50OHM_6INCH
J 0
(-2310 3110);
DISPLAY 0.638298 (-2310 3110);
PAINT ORANGE (-2310 3110);
FORCEPROP 2 LASTPROP $XRERR UNIQUE?
J 0
(-1520 3100);
DISPLAY 0.638298 (-1520 3100);
PAINT MONO (-1520 3100);
DISPLAY INVISIBLE (-1520 3100);
WIRE 16 -1 (-2525 3500)(-1550 3500);
FORCEPROP 2 LAST SIG_NAME L10_50OHM_6INCH
J 0
(-2310 3510);
DISPLAY 0.638298 (-2310 3510);
PAINT ORANGE (-2310 3510);
FORCEPROP 2 LASTPROP $XRERR UNIQUE?
J 0
(-1520 3500);
DISPLAY 0.638298 (-1520 3500);
PAINT MONO (-1520 3500);
DISPLAY INVISIBLE (-1520 3500);
WIRE 16 -1 (-2150 4250)(-1175 4250);
FORCEPROP 2 LAST SIG_NAME L14_100OHM_6INCH_DP
J 0
(-1935 4260);
DISPLAY 0.638298 (-1935 4260);
PAINT ORANGE (-1935 4260);
FORCEPROP 2 LASTPROP $XRERR UNIQUE?
J 0
(-1145 4250);
DISPLAY 0.638298 (-1145 4250);
PAINT MONO (-1145 4250);
DISPLAY INVISIBLE (-1145 4250);
WIRE 16 -1 (-5775 5725)(-4800 5725);
FORCEPROP 2 LAST SIG_NAME L3_73OHM_6INCH_DP
J 0
(-5560 5735);
DISPLAY 0.638298 (-5560 5735);
PAINT ORANGE (-5560 5735);
FORCEPROP 2 LASTPROP $XRERR UNIQUE?
J 0
(-4770 5725);
DISPLAY 0.638298 (-4770 5725);
PAINT MONO (-4770 5725);
DISPLAY INVISIBLE (-4770 5725);
WIRE 16 -1 (-5775 5625)(-4800 5625);
FORCEPROP 2 LAST SIG_NAME L3_73OHM_6INCH_DN
J 0
(-5560 5635);
DISPLAY 0.638298 (-5560 5635);
PAINT ORANGE (-5560 5635);
FORCEPROP 2 LASTPROP $XRERR UNIQUE?
J 0
(-4770 5625);
DISPLAY 0.638298 (-4770 5625);
PAINT MONO (-4770 5625);
DISPLAY INVISIBLE (-4770 5625);
WIRE 16 -1 (-5775 5350)(-4800 5350);
FORCEPROP 2 LAST SIG_NAME L5_73OHM_6INCH_DP
J 0
(-5560 5360);
DISPLAY 0.638298 (-5560 5360);
PAINT ORANGE (-5560 5360);
FORCEPROP 2 LASTPROP $XRERR UNIQUE?
J 0
(-4770 5350);
DISPLAY 0.638298 (-4770 5350);
PAINT MONO (-4770 5350);
DISPLAY INVISIBLE (-4770 5350);
WIRE 16 -1 (-4300 2650)(-3325 2650);
FORCEPROP 2 LAST SIG_NAME L5_50OHM_6INCH
J 0
(-4085 2660);
DISPLAY 0.638298 (-4085 2660);
PAINT ORANGE (-4085 2660);
FORCEPROP 2 LASTPROP $XRERR UNIQUE?
J 0
(-3295 2650);
DISPLAY 0.638298 (-3295 2650);
PAINT MONO (-3295 2650);
DISPLAY INVISIBLE (-3295 2650);
WIRE 16 -1 (-7725 4625)(-6750 4625);
FORCEPROP 2 LAST SIG_NAME L12_85OHM_6INCH_DP
J 0
(-7510 4635);
DISPLAY 0.638298 (-7510 4635);
PAINT ORANGE (-7510 4635);
FORCEPROP 2 LASTPROP $XRERR UNIQUE?
J 0
(-6720 4625);
DISPLAY 0.638298 (-6720 4625);
PAINT MONO (-6720 4625);
DISPLAY INVISIBLE (-6720 4625);
WIRE 16 -1 (-7750 4975)(-6775 4975);
FORCEPROP 2 LAST SIG_NAME L10_85OHM_6INCH_DP
J 0
(-7535 4985);
DISPLAY 0.638298 (-7535 4985);
PAINT ORANGE (-7535 4985);
FORCEPROP 2 LASTPROP $XRERR UNIQUE?
J 0
(-6745 4975);
DISPLAY 0.638298 (-6745 4975);
PAINT MONO (-6745 4975);
DISPLAY INVISIBLE (-6745 4975);
WIRE 16 -1 (-7750 4875)(-6775 4875);
FORCEPROP 2 LAST SIG_NAME L10_85OHM_6INCH_DN
J 0
(-7535 4885);
DISPLAY 0.638298 (-7535 4885);
PAINT ORANGE (-7535 4885);
FORCEPROP 2 LASTPROP $XRERR UNIQUE?
J 0
(-6745 4875);
DISPLAY 0.638298 (-6745 4875);
PAINT MONO (-6745 4875);
DISPLAY INVISIBLE (-6745 4875);
WIRE 16 -1 (-7725 4525)(-6750 4525);
FORCEPROP 2 LAST SIG_NAME L12_85OHM_6INCH_DN
J 0
(-7510 4535);
DISPLAY 0.638298 (-7510 4535);
PAINT ORANGE (-7510 4535);
FORCEPROP 2 LASTPROP $XRERR UNIQUE?
J 0
(-6720 4525);
DISPLAY 0.638298 (-6720 4525);
PAINT MONO (-6720 4525);
DISPLAY INVISIBLE (-6720 4525);
WIRE 16 -1 (-8075 3550)(-7100 3550);
FORCEPROP 2 LAST SIG_NAME L1_40OHM_6INCH
J 0
(-7860 3560);
DISPLAY 0.638298 (-7860 3560);
PAINT ORANGE (-7860 3560);
FORCEPROP 2 LASTPROP $XRERR UNIQUE?
J 0
(-7070 3550);
DISPLAY 0.638298 (-7070 3550);
PAINT MONO (-7070 3550);
DISPLAY INVISIBLE (-7070 3550);
WIRE 16 -1 (-6300 2650)(-5325 2650);
FORCEPROP 2 LAST SIG_NAME L14_40OHM_6INCH
J 0
(-6085 2660);
DISPLAY 0.638298 (-6085 2660);
PAINT ORANGE (-6085 2660);
FORCEPROP 2 LASTPROP $XRERR UNIQUE?
J 0
(-5295 2650);
DISPLAY 0.638298 (-5295 2650);
PAINT MONO (-5295 2650);
DISPLAY INVISIBLE (-5295 2650);
WIRE 16 -1 (-6300 3125)(-5325 3125);
FORCEPROP 2 LAST SIG_NAME L12_40OHM_6INCH
J 0
(-6085 3135);
DISPLAY 0.638298 (-6085 3135);
PAINT ORANGE (-6085 3135);
FORCEPROP 2 LASTPROP $XRERR UNIQUE?
J 0
(-5295 3125);
DISPLAY 0.638298 (-5295 3125);
PAINT MONO (-5295 3125);
DISPLAY INVISIBLE (-5295 3125);
WIRE 16 -1 (-6300 3525)(-5325 3525);
FORCEPROP 2 LAST SIG_NAME L10_40OHM_6INCH
J 0
(-6085 3535);
DISPLAY 0.638298 (-6085 3535);
PAINT ORANGE (-6085 3535);
FORCEPROP 2 LASTPROP $XRERR UNIQUE?
J 0
(-5295 3525);
DISPLAY 0.638298 (-5295 3525);
PAINT MONO (-5295 3525);
DISPLAY INVISIBLE (-5295 3525);
WIRE 16 -1 (-8075 3150)(-7100 3150);
FORCEPROP 2 LAST SIG_NAME L3_40OHM_6INCH
J 0
(-7860 3160);
DISPLAY 0.638298 (-7860 3160);
PAINT ORANGE (-7860 3160);
FORCEPROP 2 LASTPROP $XRERR UNIQUE?
J 0
(-7070 3150);
DISPLAY 0.638298 (-7070 3150);
PAINT MONO (-7070 3150);
DISPLAY INVISIBLE (-7070 3150);
WIRE 16 -1 (-5775 4850)(-4800 4850);
FORCEPROP 2 LAST SIG_NAME L10_73OHM_6INCH_DN
J 0
(-5560 4860);
DISPLAY 0.638298 (-5560 4860);
PAINT ORANGE (-5560 4860);
FORCEPROP 2 LASTPROP $XRERR UNIQUE?
J 0
(-4770 4850);
DISPLAY 0.638298 (-4770 4850);
PAINT MONO (-4770 4850);
DISPLAY INVISIBLE (-4770 4850);
WIRE 16 -1 (-5750 4500)(-4775 4500);
FORCEPROP 2 LAST SIG_NAME L12_73OHM_6INCH_DN
J 0
(-5535 4510);
DISPLAY 0.638298 (-5535 4510);
PAINT ORANGE (-5535 4510);
FORCEPROP 2 LASTPROP $XRERR UNIQUE?
J 0
(-4745 4500);
DISPLAY 0.638298 (-4745 4500);
PAINT MONO (-4745 4500);
DISPLAY INVISIBLE (-4745 4500);
WIRE 16 -1 (-5750 4200)(-4775 4200);
FORCEPROP 2 LAST SIG_NAME L14_73OHM_6INCH_DP
J 0
(-5535 4210);
DISPLAY 0.638298 (-5535 4210);
PAINT ORANGE (-5535 4210);
FORCEPROP 2 LASTPROP $XRERR UNIQUE?
J 0
(-4745 4200);
DISPLAY 0.638298 (-4745 4200);
PAINT MONO (-4745 4200);
DISPLAY INVISIBLE (-4745 4200);
WIRE 16 -1 (-5750 4100)(-4775 4100);
FORCEPROP 2 LAST SIG_NAME L14_73OHM_6INCH_DN
J 0
(-5535 4110);
DISPLAY 0.638298 (-5535 4110);
PAINT ORANGE (-5535 4110);
FORCEPROP 2 LASTPROP $XRERR UNIQUE?
J 0
(-4745 4100);
DISPLAY 0.638298 (-4745 4100);
PAINT MONO (-4745 4100);
DISPLAY INVISIBLE (-4745 4100);
WIRE 16 -1 (-7725 4125)(-6750 4125);
FORCEPROP 2 LAST SIG_NAME L14_85OHM_6INCH_DN
J 0
(-7510 4135);
DISPLAY 0.638298 (-7510 4135);
PAINT ORANGE (-7510 4135);
FORCEPROP 2 LASTPROP $XRERR UNIQUE?
J 0
(-6720 4125);
DISPLAY 0.638298 (-6720 4125);
PAINT MONO (-6720 4125);
DISPLAY INVISIBLE (-6720 4125);
WIRE 16 -1 (-7725 4225)(-6750 4225);
FORCEPROP 2 LAST SIG_NAME L14_85OHM_6INCH_DP
J 0
(-7510 4235);
DISPLAY 0.638298 (-7510 4235);
PAINT ORANGE (-7510 4235);
FORCEPROP 2 LASTPROP $XRERR UNIQUE?
J 0
(-6720 4225);
DISPLAY 0.638298 (-6720 4225);
PAINT MONO (-6720 4225);
DISPLAY INVISIBLE (-6720 4225);
WIRE 16 -1 (-7750 6150)(-6775 6150);
FORCEPROP 2 LAST SIG_NAME L1_85OHM_6INCH_DP
J 0
(-7535 6160);
DISPLAY 0.638298 (-7535 6160);
PAINT ORANGE (-7535 6160);
FORCEPROP 2 LASTPROP $XRERR UNIQUE?
J 0
(-6745 6150);
DISPLAY 0.638298 (-6745 6150);
PAINT MONO (-6745 6150);
DISPLAY INVISIBLE (-6745 6150);
WIRE 16 -1 (-7750 6050)(-6775 6050);
FORCEPROP 2 LAST SIG_NAME L1_85OHM_6INCH_DN
J 0
(-7535 6060);
DISPLAY 0.638298 (-7535 6060);
PAINT ORANGE (-7535 6060);
FORCEPROP 2 LASTPROP $XRERR UNIQUE?
J 0
(-6745 6050);
DISPLAY 0.638298 (-6745 6050);
PAINT MONO (-6745 6050);
DISPLAY INVISIBLE (-6745 6050);
WIRE 16 -1 (-7750 5375)(-6775 5375);
FORCEPROP 2 LAST SIG_NAME L5_85OHM_6INCH_DP
J 0
(-7535 5385);
DISPLAY 0.638298 (-7535 5385);
PAINT ORANGE (-7535 5385);
FORCEPROP 2 LASTPROP $XRERR UNIQUE?
J 0
(-6745 5375);
DISPLAY 0.638298 (-6745 5375);
PAINT MONO (-6745 5375);
DISPLAY INVISIBLE (-6745 5375);
WIRE 16 -1 (-7750 5275)(-6775 5275);
FORCEPROP 2 LAST SIG_NAME L5_85OHM_6INCH_DN
J 0
(-7535 5285);
DISPLAY 0.638298 (-7535 5285);
PAINT ORANGE (-7535 5285);
FORCEPROP 2 LASTPROP $XRERR UNIQUE?
J 0
(-6745 5275);
DISPLAY 0.638298 (-6745 5275);
PAINT MONO (-6745 5275);
DISPLAY INVISIBLE (-6745 5275);
WIRE 16 -1 (-7750 5750)(-6775 5750);
FORCEPROP 2 LAST SIG_NAME L3_85OHM_6INCH_DP
J 0
(-7535 5760);
DISPLAY 0.638298 (-7535 5760);
PAINT ORANGE (-7535 5760);
FORCEPROP 2 LASTPROP $XRERR UNIQUE?
J 0
(-6745 5750);
DISPLAY 0.638298 (-6745 5750);
PAINT MONO (-6745 5750);
DISPLAY INVISIBLE (-6745 5750);
WIRE 16 -1 (-2150 4150)(-1175 4150);
FORCEPROP 2 LAST SIG_NAME L14_100OHM_6INCH_DN
J 0
(-1935 4160);
DISPLAY 0.638298 (-1935 4160);
PAINT ORANGE (-1935 4160);
FORCEPROP 2 LASTPROP $XRERR UNIQUE?
J 0
(-1145 4150);
DISPLAY 0.638298 (-1145 4150);
PAINT MONO (-1145 4150);
DISPLAY INVISIBLE (-1145 4150);
WIRE 16 -1 (-2175 5000)(-1200 5000);
FORCEPROP 2 LAST SIG_NAME L10_100OHM_6INCH_DP
J 0
(-1960 5010);
DISPLAY 0.638298 (-1960 5010);
PAINT ORANGE (-1960 5010);
FORCEPROP 2 LASTPROP $XRERR UNIQUE?
J 0
(-1170 5000);
DISPLAY 0.638298 (-1170 5000);
PAINT MONO (-1170 5000);
DISPLAY INVISIBLE (-1170 5000);
WIRE 16 -1 (-2150 4550)(-1175 4550);
FORCEPROP 2 LAST SIG_NAME L12_100OHM_6INCH_DN
J 0
(-1935 4560);
DISPLAY 0.638298 (-1935 4560);
PAINT ORANGE (-1935 4560);
FORCEPROP 2 LASTPROP $XRERR UNIQUE?
J 0
(-1145 4550);
DISPLAY 0.638298 (-1145 4550);
PAINT MONO (-1145 4550);
DISPLAY INVISIBLE (-1145 4550);
WIRE 16 -1 (-2150 4650)(-1175 4650);
FORCEPROP 2 LAST SIG_NAME L12_100OHM_6INCH_DP
J 0
(-1935 4660);
DISPLAY 0.638298 (-1935 4660);
PAINT ORANGE (-1935 4660);
FORCEPROP 2 LASTPROP $XRERR UNIQUE?
J 0
(-1145 4650);
DISPLAY 0.638298 (-1145 4650);
PAINT MONO (-1145 4650);
DISPLAY INVISIBLE (-1145 4650);
WIRE 16 -1 (-5775 6125)(-4800 6125);
FORCEPROP 2 LAST SIG_NAME L1_73OHM_6INCH_DP
J 0
(-5560 6135);
DISPLAY 0.638298 (-5560 6135);
PAINT ORANGE (-5560 6135);
FORCEPROP 2 LASTPROP $XRERR UNIQUE?
J 0
(-4770 6125);
DISPLAY 0.638298 (-4770 6125);
PAINT MONO (-4770 6125);
DISPLAY INVISIBLE (-4770 6125);
WIRE 16 -1 (-5775 6025)(-4800 6025);
FORCEPROP 2 LAST SIG_NAME L1_73OHM_6INCH_DN
J 0
(-5560 6035);
DISPLAY 0.638298 (-5560 6035);
PAINT ORANGE (-5560 6035);
FORCEPROP 2 LASTPROP $XRERR UNIQUE?
J 0
(-4770 6025);
DISPLAY 0.638298 (-4770 6025);
PAINT MONO (-4770 6025);
DISPLAY INVISIBLE (-4770 6025);
WIRE 16 -1 (-5775 5250)(-4800 5250);
FORCEPROP 2 LAST SIG_NAME L5_73OHM_6INCH_DN
J 0
(-5560 5260);
DISPLAY 0.638298 (-5560 5260);
PAINT ORANGE (-5560 5260);
FORCEPROP 2 LASTPROP $XRERR UNIQUE?
J 0
(-4770 5250);
DISPLAY 0.638298 (-4770 5250);
PAINT MONO (-4770 5250);
DISPLAY INVISIBLE (-4770 5250);
WIRE 16 -1 (-5775 4950)(-4800 4950);
FORCEPROP 2 LAST SIG_NAME L10_73OHM_6INCH_DP
J 0
(-5560 4960);
DISPLAY 0.638298 (-5560 4960);
PAINT ORANGE (-5560 4960);
FORCEPROP 2 LASTPROP $XRERR UNIQUE?
J 0
(-4770 4950);
DISPLAY 0.638298 (-4770 4950);
PAINT MONO (-4770 4950);
DISPLAY INVISIBLE (-4770 4950);
WIRE 16 -1 (-5750 4600)(-4775 4600);
FORCEPROP 2 LAST SIG_NAME L12_73OHM_6INCH_DP
J 0
(-5535 4610);
DISPLAY 0.638298 (-5535 4610);
PAINT ORANGE (-5535 4610);
FORCEPROP 2 LASTPROP $XRERR UNIQUE?
J 0
(-4745 4600);
DISPLAY 0.638298 (-4745 4600);
PAINT MONO (-4745 4600);
DISPLAY INVISIBLE (-4745 4600);
WIRE 16 -1 (-2175 4900)(-1200 4900);
FORCEPROP 2 LAST SIG_NAME L10_100OHM_6INCH_DN
J 0
(-1960 4910);
DISPLAY 0.638298 (-1960 4910);
PAINT ORANGE (-1960 4910);
FORCEPROP 2 LASTPROP $XRERR UNIQUE?
J 0
(-1170 4900);
DISPLAY 0.638298 (-1170 4900);
PAINT MONO (-1170 4900);
DISPLAY INVISIBLE (-1170 4900);
WIRE 16 -1 (-2175 6075)(-1200 6075);
FORCEPROP 2 LAST SIG_NAME L1_100OHM_6INCH_DN
J 0
(-1960 6085);
DISPLAY 0.638298 (-1960 6085);
PAINT ORANGE (-1960 6085);
FORCEPROP 2 LASTPROP $XRERR UNIQUE?
J 0
(-1170 6075);
DISPLAY 0.638298 (-1170 6075);
PAINT MONO (-1170 6075);
DISPLAY INVISIBLE (-1170 6075);
WIRE 16 -1 (-2175 6175)(-1200 6175);
FORCEPROP 2 LAST SIG_NAME L1_100OHM_6INCH_DP
J 0
(-1960 6185);
DISPLAY 0.638298 (-1960 6185);
PAINT ORANGE (-1960 6185);
FORCEPROP 2 LASTPROP $XRERR UNIQUE?
J 0
(-1170 6175);
DISPLAY 0.638298 (-1170 6175);
PAINT MONO (-1170 6175);
DISPLAY INVISIBLE (-1170 6175);
DOT 1 (-6450 6025);
DOT 1 (-6450 5625);
DOT 1 (-6450 5250);
DOT 1 (-6450 4850);
DOT 1 (-6425 4500);
DOT 1 (-6425 4100);
DOT 1 (-2825 4150);
DOT 1 (-2825 4550);
DOT 1 (-2850 6075);
DOT 1 (-4625 4500);
DOT 1 (-4650 5625);
DOT 1 (-8400 4125);
DOT 1 (-8400 4525);
DOT 1 (-8425 4875);
DOT 1 (-8425 5275);
DOT 1 (-8425 5650);
DOT 1 (-8425 6050);
DOT 1 (-2850 4900);
FORCENOTE
TP FAB3-DVT CORRECT THE NET NAME 20161128
(-3850 5550) 0;
DISPLAY LEFT (-3850 5550);
DISPLAY 0.638298 (-3850 5550);
PAINT RED (-3850 5550);
FORCENOTE
TP FAB3-DVT CORRECT THE NET NAME 20161124
(-3925 4400) 0;
DISPLAY LEFT (-3925 4400);
DISPLAY 0.638298 (-3925 4400);
PAINT RED (-3925 4400);
FORCENOTE
TP FAB3-DVT ADD COUPON SYMBOLS 20161118
(-3050 1925) 0;
DISPLAY LEFT (-3050 1925);
DISPLAY 1.021277 (-3050 1925);
PAINT RED (-3050 1925);
QUIT
